FILE_TYPE = MACRO_DRAWING;
SET COLOR_WIRE YELLOW;
SET COLOR_PROP MONO;
SET COLOR_DOT WHITE;
SET COLOR_ARC YELLOW;
SET COLOR_BODY GREEN;
SET COLOR_NOTE MONO;
SET PROP_DISPLAY VALUE;
SET PAGE_NUMBER P215;
FORCEADD OFFPAGE..2
(4325 2650);
FORCEPROP 2 LAST $XR0 221 
J 0
(4514 2650);
DISPLAY 0.638298 (4514 2650);
PAINT MONO (4514 2650);
FORCEPROP 2 LAST ROOM VDDQ_ABC_PWR_VR
J 0
(3900 2725);
DISPLAY 1.361702 (3900 2725);
PAINT ORANGE (3900 2725);
DISPLAY INVISIBLE (3900 2725);
FORCEPROP 1 LAST COMMENT_BODY TRUE
J 0
(4280 2555);
DISPLAY 1.170213 (4280 2555);
PAINT GREEN (4280 2555);
DISPLAY INVISIBLE (4280 2555);
FORCEPROP 2 LAST CDS_LIB mstr_standard
J 0
(4325 2650);
PAINT ORANGE (4325 2650);
DISPLAY INVISIBLE (4325 2650);
FORCEPROP 2 LAST PATH I284
J 0
(4525 2700);
DISPLAY 1.021277 (4525 2700);
PAINT ORANGE (4525 2700);
DISPLAY INVISIBLE (4525 2700);
FORCEPROP 1 LAST OFFPAGE TRUE
J 0
(4650 2525);
DISPLAY 1.170213 (4650 2525);
PAINT GREEN (4650 2525);
DISPLAY INVISIBLE (4650 2525);
FORCEADD OFFPAGE..2
(4325 2550);
FORCEPROP 2 LAST $XR0 94 
J 0
(4514 2550);
DISPLAY 0.638298 (4514 2550);
PAINT MONO (4514 2550);
FORCEPROP 2 LAST $XR1 119 
J 0
(4604 2550);
DISPLAY 0.638298 (4604 2550);
PAINT MONO (4604 2550);
FORCEPROP 2 LAST $XR2 145 
J 0
(4724 2550);
DISPLAY 0.638298 (4724 2550);
PAINT MONO (4724 2550);
FORCEPROP 2 LAST ROOM VDDQ_ABC_PWR_VR
J 0
(3900 2625);
DISPLAY 1.361702 (3900 2625);
PAINT ORANGE (3900 2625);
DISPLAY INVISIBLE (3900 2625);
FORCEPROP 1 LAST COMMENT_BODY TRUE
J 0
(4280 2455);
DISPLAY 1.170213 (4280 2455);
PAINT GREEN (4280 2455);
DISPLAY INVISIBLE (4280 2455);
FORCEPROP 2 LAST CDS_LIB mstr_standard
J 0
(4325 2550);
PAINT ORANGE (4325 2550);
DISPLAY INVISIBLE (4325 2550);
FORCEPROP 1 LAST OFFPAGE TRUE
J 0
(4650 2425);
DISPLAY 1.170213 (4650 2425);
PAINT GREEN (4650 2425);
DISPLAY INVISIBLE (4650 2425);
FORCEPROP 2 LAST PATH I285
J 0
(4725 2600);
DISPLAY 1.021277 (4725 2600);
PAINT ORANGE (4725 2600);
DISPLAY INVISIBLE (4725 2600);
FORCEADD OFFPAGE..2
(4325 2500);
FORCEPROP 2 LAST $XR0 194 
J 0
(4514 2500);
DISPLAY 0.638298 (4514 2500);
PAINT MONO (4514 2500);
FORCEPROP 2 LAST $XR1 218 
J 0
(4634 2500);
DISPLAY 0.638298 (4634 2500);
PAINT MONO (4634 2500);
FORCEPROP 2 LAST $XR2 21 
J 0
(4754 2500);
DISPLAY 0.638298 (4754 2500);
PAINT MONO (4754 2500);
FORCEPROP 2 LAST ROOM VDDQ_ABC_PWR_VR
J 0
(3900 2575);
DISPLAY 1.361702 (3900 2575);
PAINT ORANGE (3900 2575);
DISPLAY INVISIBLE (3900 2575);
FORCEPROP 1 LAST COMMENT_BODY TRUE
J 0
(4280 2405);
DISPLAY 1.170213 (4280 2405);
PAINT GREEN (4280 2405);
DISPLAY INVISIBLE (4280 2405);
FORCEPROP 2 LAST CDS_LIB mstr_standard
J 0
(4325 2500);
PAINT ORANGE (4325 2500);
DISPLAY INVISIBLE (4325 2500);
FORCEPROP 1 LAST OFFPAGE TRUE
J 0
(4650 2375);
DISPLAY 1.170213 (4650 2375);
PAINT GREEN (4650 2375);
DISPLAY INVISIBLE (4650 2375);
FORCEPROP 2 LAST PATH I286
J 0
(4650 2550);
DISPLAY 1.021277 (4650 2550);
PAINT ORANGE (4650 2550);
DISPLAY INVISIBLE (4650 2550);
FORCEADD OFFPAGE..1
R 2
(4325 2150);
FORCEPROP 2 LAST $XR0 138 
J 0
(4511 2150);
DISPLAY 0.638298 (4511 2150);
PAINT MONO (4511 2150);
FORCEPROP 2 LAST $XR1 159 
J 0
(4631 2150);
DISPLAY 0.638298 (4631 2150);
PAINT MONO (4631 2150);
FORCEPROP 2 LAST $XR2 211 
J 0
(4751 2150);
DISPLAY 0.638298 (4751 2150);
PAINT MONO (4751 2150);
FORCEPROP 2 LAST $XR3 213 
J 0
(4871 2150);
DISPLAY 0.638298 (4871 2150);
PAINT MONO (4871 2150);
FORCEPROP 2 LAST $XR4 235 
J 0
(4991 2150);
DISPLAY 0.638298 (4991 2150);
PAINT MONO (4991 2150);
FORCEPROP 2 LAST $XR5 193 
J 0
(5111 2150);
DISPLAY 0.638298 (5111 2150);
PAINT MONO (5111 2150);
FORCEPROP 2 LAST $XR6 194 
J 0
(5231 2150);
DISPLAY 0.638298 (5231 2150);
PAINT MONO (5231 2150);
FORCEPROP 2 LAST $XR7 201 
J 0
(5351 2150);
DISPLAY 0.638298 (5351 2150);
PAINT MONO (5351 2150);
FORCEPROP 2 LAST $XR8 206 
J 0
(5471 2150);
DISPLAY 0.638298 (5471 2150);
PAINT MONO (5471 2150);
FORCEPROP 2 LAST $XR9 218 
J 0
(5591 2150);
DISPLAY 0.638298 (5591 2150);
PAINT MONO (5591 2150);
FORCEPROP 2 LAST $XR10 223 
J 0
(4631 2114);
DISPLAY 0.638298 (4631 2114);
PAINT MONO (4631 2114);
FORCEPROP 2 LAST $XR11 226 
J 0
(4751 2114);
DISPLAY 0.638298 (4751 2114);
PAINT MONO (4751 2114);
FORCEPROP 1 LAST OFFPAGE TRUE
J 2
(4000 2025);
DISPLAY 1.170213 (4000 2025);
PAINT GREEN (4000 2025);
DISPLAY INVISIBLE (4000 2025);
FORCEPROP 2 LAST ROOM VDDQ_ABC_PWR_VR
J 0
(3900 2225);
DISPLAY 1.361702 (3900 2225);
PAINT ORANGE (3900 2225);
DISPLAY INVISIBLE (3900 2225);
FORCEPROP 1 LAST COMMENT_BODY TRUE
J 2
(4200 2050);
DISPLAY 1.170213 (4200 2050);
PAINT GREEN (4200 2050);
DISPLAY INVISIBLE (4200 2050);
FORCEPROP 2 LAST CDS_LIB mstr_standard
J 0
(4325 2150);
PAINT ORANGE (4325 2150);
DISPLAY INVISIBLE (4325 2150);
FORCEPROP 2 LAST PATH I287
J 0
(4875 2225);
DISPLAY 1.021277 (4875 2225);
PAINT ORANGE (4875 2225);
DISPLAY INVISIBLE (4875 2225);
FORCEADD OFFPAGE..3
(4325 2100);
FORCEPROP 2 LAST $XR0 138 
J 0
(4539 2100);
DISPLAY 0.638298 (4539 2100);
PAINT MONO (4539 2100);
FORCEPROP 2 LAST $XR1 159 
J 0
(4539 2064);
DISPLAY 0.638298 (4539 2064);
PAINT MONO (4539 2064);
FORCEPROP 2 LAST $XR2 193 
J 0
(4659 2064);
DISPLAY 0.638298 (4659 2064);
PAINT MONO (4659 2064);
FORCEPROP 2 LAST $XR3 194 
J 0
(4779 2064);
DISPLAY 0.638298 (4779 2064);
PAINT MONO (4779 2064);
FORCEPROP 2 LAST $XR4 201 
J 0
(4899 2064);
DISPLAY 0.638298 (4899 2064);
PAINT MONO (4899 2064);
FORCEPROP 2 LAST $XR5 206 
J 0
(5019 2064);
DISPLAY 0.638298 (5019 2064);
PAINT MONO (5019 2064);
FORCEPROP 2 LAST $XR6 211 
J 0
(5139 2064);
DISPLAY 0.638298 (5139 2064);
PAINT MONO (5139 2064);
FORCEPROP 2 LAST $XR7 213 
J 0
(5259 2064);
DISPLAY 0.638298 (5259 2064);
PAINT MONO (5259 2064);
FORCEPROP 2 LAST $XR8 218 
J 0
(5379 2064);
DISPLAY 0.638298 (5379 2064);
PAINT MONO (5379 2064);
FORCEPROP 2 LAST $XR9 223 
J 0
(4899 2100);
DISPLAY 0.638298 (4899 2100);
PAINT MONO (4899 2100);
FORCEPROP 2 LAST $XR10 226 
J 0
(5019 2100);
DISPLAY 0.638298 (5019 2100);
PAINT MONO (5019 2100);
FORCEPROP 2 LAST $XR11 235 
J 0
(5139 2100);
DISPLAY 0.638298 (5139 2100);
PAINT MONO (5139 2100);
FORCEPROP 2 LAST ROOM VDDQ_ABC_PWR_VR
J 0
(3925 2175);
DISPLAY 1.361702 (3925 2175);
PAINT ORANGE (3925 2175);
DISPLAY INVISIBLE (3925 2175);
FORCEPROP 1 LAST OFFPAGE TRUE
J 0
(4650 1975);
DISPLAY 1.170213 (4650 1975);
PAINT GREEN (4650 1975);
DISPLAY INVISIBLE (4650 1975);
FORCEPROP 1 LAST COMMENT_BODY TRUE
J 0
(4275 2000);
DISPLAY 1.170213 (4275 2000);
PAINT GREEN (4275 2000);
DISPLAY INVISIBLE (4275 2000);
FORCEPROP 2 LAST CDS_LIB mstr_standard
J 0
(4325 2100);
PAINT ORANGE (4325 2100);
DISPLAY INVISIBLE (4325 2100);
FORCEPROP 2 LAST PATH I288
J 0
(5150 2150);
DISPLAY 1.021277 (5150 2150);
PAINT ORANGE (5150 2150);
DISPLAY INVISIBLE (5150 2150);
FORCEADD OFFPAGE..2
(4350 1850);
FORCEPROP 2 LAST $XR0 215 
J 0
(4539 1850);
DISPLAY 0.638298 (4539 1850);
PAINT MONO (4539 1850);
FORCEPROP 2 LAST ROOM VDDQ_ABC_PWR_VR
J 0
(3925 1925);
DISPLAY 1.361702 (3925 1925);
PAINT ORANGE (3925 1925);
DISPLAY INVISIBLE (3925 1925);
FORCEPROP 1 LAST COMMENT_BODY TRUE
J 0
(4305 1755);
DISPLAY 1.170213 (4305 1755);
PAINT GREEN (4305 1755);
DISPLAY INVISIBLE (4305 1755);
FORCEPROP 2 LAST CDS_LIB mstr_standard
J 0
(4350 1850);
PAINT ORANGE (4350 1850);
DISPLAY INVISIBLE (4350 1850);
FORCEPROP 2 LAST PATH I289
J 0
(4550 1900);
DISPLAY 1.021277 (4550 1900);
PAINT ORANGE (4550 1900);
DISPLAY INVISIBLE (4550 1900);
FORCEPROP 1 LAST OFFPAGE TRUE
J 0
(4675 1725);
DISPLAY 1.170213 (4675 1725);
PAINT GREEN (4675 1725);
DISPLAY INVISIBLE (4675 1725);
FORCEADD OFFPAGE..3
(4325 1800);
FORCEPROP 2 LAST $XR0 21 
J 0
(4539 1800);
DISPLAY 0.638298 (4539 1800);
PAINT MONO (4539 1800);
FORCEPROP 2 LAST $XR1 194 
J 0
(4629 1800);
DISPLAY 0.638298 (4629 1800);
PAINT MONO (4629 1800);
FORCEPROP 2 LAST $XR2 218 
J 0
(4749 1800);
DISPLAY 0.638298 (4749 1800);
PAINT MONO (4749 1800);
FORCEPROP 2 LAST ROOM VDDQ_ABC_PWR_VR
J 0
(3925 1875);
DISPLAY 1.361702 (3925 1875);
PAINT ORANGE (3925 1875);
DISPLAY INVISIBLE (3925 1875);
FORCEPROP 1 LAST COMMENT_BODY TRUE
J 0
(4275 1700);
DISPLAY 1.170213 (4275 1700);
PAINT GREEN (4275 1700);
DISPLAY INVISIBLE (4275 1700);
FORCEPROP 2 LAST CDS_LIB mstr_standard
J 0
(4325 1800);
PAINT ORANGE (4325 1800);
DISPLAY INVISIBLE (4325 1800);
FORCEPROP 2 LAST PATH I290
J 0
(4650 1850);
DISPLAY 1.021277 (4650 1850);
PAINT ORANGE (4650 1850);
DISPLAY INVISIBLE (4650 1850);
FORCEPROP 1 LAST OFFPAGE TRUE
J 0
(4650 1675);
DISPLAY 1.170213 (4650 1675);
PAINT GREEN (4650 1675);
DISPLAY INVISIBLE (4650 1675);
FORCEADD OFFPAGE..2
(4350 1600);
FORCEPROP 2 LAST $XR0 216 
J 0
(4539 1600);
DISPLAY 0.638298 (4539 1600);
PAINT MONO (4539 1600);
FORCEPROP 2 LAST ROOM VDDQ_ABC_PWR_VR
J 0
(3925 1675);
DISPLAY 1.361702 (3925 1675);
PAINT ORANGE (3925 1675);
DISPLAY INVISIBLE (3925 1675);
FORCEPROP 1 LAST COMMENT_BODY TRUE
J 0
(4305 1505);
DISPLAY 1.170213 (4305 1505);
PAINT GREEN (4305 1505);
DISPLAY INVISIBLE (4305 1505);
FORCEPROP 2 LAST CDS_LIB mstr_standard
J 0
(4350 1600);
PAINT ORANGE (4350 1600);
DISPLAY INVISIBLE (4350 1600);
FORCEPROP 2 LAST PATH I291
J 0
(4550 1650);
DISPLAY 1.021277 (4550 1650);
PAINT ORANGE (4550 1650);
DISPLAY INVISIBLE (4550 1650);
FORCEPROP 1 LAST OFFPAGE TRUE
J 0
(4675 1475);
DISPLAY 1.170213 (4675 1475);
PAINT GREEN (4675 1475);
DISPLAY INVISIBLE (4675 1475);
FORCEADD OFFPAGE..2
(4350 1550);
FORCEPROP 2 LAST $XR0 216 
J 0
(4539 1550);
DISPLAY 0.638298 (4539 1550);
PAINT MONO (4539 1550);
FORCEPROP 2 LAST ROOM VDDQ_ABC_PWR_VR
J 0
(3925 1625);
DISPLAY 1.361702 (3925 1625);
PAINT ORANGE (3925 1625);
DISPLAY INVISIBLE (3925 1625);
FORCEPROP 1 LAST COMMENT_BODY TRUE
J 0
(4305 1455);
DISPLAY 1.170213 (4305 1455);
PAINT GREEN (4305 1455);
DISPLAY INVISIBLE (4305 1455);
FORCEPROP 2 LAST CDS_LIB mstr_standard
J 0
(4350 1550);
PAINT ORANGE (4350 1550);
DISPLAY INVISIBLE (4350 1550);
FORCEPROP 2 LAST PATH I292
J 0
(4550 1600);
DISPLAY 1.021277 (4550 1600);
PAINT ORANGE (4550 1600);
DISPLAY INVISIBLE (4550 1600);
FORCEPROP 1 LAST OFFPAGE TRUE
J 0
(4675 1425);
DISPLAY 1.170213 (4675 1425);
PAINT GREEN (4675 1425);
DISPLAY INVISIBLE (4675 1425);
FORCEADD OFFPAGE..1
R 2
(3550 675);
FORCEPROP 2 LAST $XR0 215 
J 0
(3736 675);
DISPLAY 0.638298 (3736 675);
PAINT MONO (3736 675);
FORCEPROP 2 LAST CDS_LIB mstr_standard
J 2
(3550 675);
PAINT ORANGE (3550 675);
DISPLAY INVISIBLE (3550 675);
FORCEPROP 2 LAST ROOM VDDQ_ABC_PWR_VR
J 0
(3125 750);
DISPLAY 1.361702 (3125 750);
PAINT ORANGE (3125 750);
DISPLAY INVISIBLE (3125 750);
FORCEPROP 1 LAST OFFPAGE TRUE
J 2
(3225 550);
DISPLAY 1.170213 (3225 550);
PAINT GREEN (3225 550);
DISPLAY INVISIBLE (3225 550);
FORCEPROP 1 LAST COMMENT_BODY TRUE
J 2
(3425 575);
DISPLAY 1.170213 (3425 575);
PAINT GREEN (3425 575);
DISPLAY INVISIBLE (3425 575);
FORCEPROP 2 LAST PATH I293
J 0
(3750 725);
DISPLAY 1.021277 (3750 725);
PAINT ORANGE (3750 725);
DISPLAY INVISIBLE (3750 725);
FORCEADD PVCCIO_CPU0..1
(4100 3150);
FORCEPROP 3 LASTPIN (4100 3100) SIG_NAME PVCCIO_CPU0\g
J 0
(4110 3110);
DISPLAY 0.659574 (4110 3110);
PAINT MONO (4110 3110);
DISPLAY INVISIBLE (4110 3110);
FORCEPROP 1 LAST BODY_TYPE PLUMBING
J 0
(4055 3107);
DISPLAY 0.340426 (4055 3107);
PAINT GREEN (4055 3107);
DISPLAY INVISIBLE (4055 3107);
FORCEPROP 1 LAST VOLTAGE 1.1V
J 0
(4055 3107);
DISPLAY 0.340426 (4055 3107);
PAINT SKYBLUE (4055 3107);
DISPLAY INVISIBLE (4055 3107);
FORCEPROP 2 LAST CDS_LIB mstr_symbols
J 0
(4100 3150);
PAINT ORANGE (4100 3150);
DISPLAY INVISIBLE (4100 3150);
FORCEPROP 1 LAST PATH I294
J 0
(4150 3175);
DISPLAY 0.872340 (4150 3175);
PAINT AQUA (4150 3175);
DISPLAY INVISIBLE (4150 3175);
FORCEPROP 1 LAST HDL_POWER PVCCIO_CPU0
J 1
(4100 3200);
DISPLAY 0.872340 (4100 3200);
PAINT GREEN (4100 3200);
DISPLAY INVISIBLE (4100 3200);
FORCEADD RES..2
(4100 2925);
FORCEPROP 1 LAST PACK_TYPE 0402
J 0
(4140 2750);
DISPLAY 0.617021 (4140 2750);
PAINT SKYBLUE (4140 2750);
FORCEPROP 1 LASTPIN (4100 3025) $PN 1
J 0
(4105 2987);
DISPLAY 0.617021 (4105 2987);
PAINT ORANGE (4105 2987);
FORCEPROP 1 LASTPIN (4100 2825) $PN 2
J 0
(4105 2835);
DISPLAY 0.617021 (4105 2835);
PAINT ORANGE (4105 2835);
FORCEPROP 1 LAST WATTAGE 1/16W
J 0
(4140 2900);
DISPLAY 0.617021 (4140 2900);
PAINT SKYBLUE (4140 2900);
FORCEPROP 1 LAST VALUE 100.0
J 0
(4145 3000);
DISPLAY 0.617021 (4145 3000);
PAINT SKYBLUE (4145 3000);
FORCEPROP 1 LAST TOLERANCE 1%
J 0
(4145 2950);
DISPLAY 0.617021 (4145 2950);
PAINT SKYBLUE (4145 2950);
FORCEPROP 1 LAST MATERIAL CHIP
J 0
(4140 2850);
DISPLAY 0.617021 (4140 2850);
PAINT SKYBLUE (4140 2850);
FORCEPROP 1 LAST PART_NUMBER G21796-017
J 0
(4140 2800);
DISPLAY 0.617021 (4140 2800);
PAINT BLUE (4140 2800);
FORCEPROP 1 LAST LOCATION R3U2
J 0
(4145 3050);
DISPLAY 0.617021 (4145 3050);
PAINT AQUA (4145 3050);
FORCEPROP 2 LAST CDS_LIB mstr_discrete
J 0
(4100 2925);
PAINT ORANGE (4100 2925);
DISPLAY INVISIBLE (4100 2925);
FORCEPROP 2 LAST CDS_LOCATION R3U2
J 0
(4145 3050);
DISPLAY 0.617021 (4145 3050);
PAINT AQUA (4145 3050);
DISPLAY INVISIBLE (4145 3050);
FORCEPROP 2 LAST SEC_TYPE 0402
J 0
(4150 3175);
DISPLAY 1.021277 (4150 3175);
PAINT ORANGE (4150 3175);
DISPLAY INVISIBLE (4150 3175);
FORCEPROP 2 LAST SEC 1
J 0
(4150 3175);
DISPLAY 0.680851 (4150 3175);
PAINT MONO (4150 3175);
DISPLAY INVISIBLE (4150 3175);
FORCEPROP 1 LAST PATH I295
J 0
(4150 3100);
DISPLAY 0.978723 (4150 3100);
PAINT WHITE (4150 3100);
DISPLAY INVISIBLE (4150 3100);
FORCEPROP 2 LAST ROOM VDDQ_ABC_PWR_VR
J 0
(4150 3100);
DISPLAY 1.361702 (4150 3100);
PAINT ORANGE (4150 3100);
DISPLAY INVISIBLE (4150 3100);
FORCEADD RES..1
(3500 2650);
FORCEPROP 1 LAST PACK_TYPE 0402
J 0
(3325 2575);
DISPLAY 0.617021 (3325 2575);
PAINT SKYBLUE (3325 2575);
FORCEPROP 1 LAST VALUE 22.1
J 2
(3425 2625);
DISPLAY 0.617021 (3425 2625);
PAINT SKYBLUE (3425 2625);
FORCEPROP 1 LASTPIN (3400 2650) $PN 1
J 0
(3412 2662);
DISPLAY 0.617021 (3412 2662);
PAINT ORANGE (3412 2662);
FORCEPROP 1 LAST WATTAGE 1/16W
J 2
(3575 2600);
DISPLAY 0.617021 (3575 2600);
PAINT SKYBLUE (3575 2600);
FORCEPROP 1 LASTPIN (3600 2650) $PN 2
J 0
(3562 2662);
DISPLAY 0.617021 (3562 2662);
PAINT ORANGE (3562 2662);
FORCEPROP 1 LAST MATERIAL CHIP
J 0
(3575 2575);
DISPLAY 0.617021 (3575 2575);
PAINT SKYBLUE (3575 2575);
FORCEPROP 1 LAST TOLERANCE 1.0%
J 0
(3575 2625);
DISPLAY 0.617021 (3575 2625);
PAINT SKYBLUE (3575 2625);
FORCEPROP 1 LAST PART_NUMBER G21796-250
J 0
(3450 2750);
DISPLAY 0.617021 (3450 2750);
PAINT BLUE (3450 2750);
FORCEPROP 1 LAST LOCATION R7F24
J 0
(3450 2700);
DISPLAY 0.617021 (3450 2700);
PAINT AQUA (3450 2700);
FORCEPROP 2 LAST ROOM VDDQ_ABC_PWR_VR
J 0
(3450 2750);
DISPLAY 1.361702 (3450 2750);
PAINT ORANGE (3450 2750);
DISPLAY INVISIBLE (3450 2750);
FORCEPROP 2 LAST CDS_LOCATION R7F24
J 0
(3450 2700);
DISPLAY 0.617021 (3450 2700);
PAINT AQUA (3450 2700);
DISPLAY INVISIBLE (3450 2700);
FORCEPROP 2 LAST CDS_LIB mstr_discrete
J 0
(3500 2650);
PAINT MONO (3500 2650);
DISPLAY INVISIBLE (3500 2650);
FORCEPROP 1 LAST PATH I296
J 0
(3450 2800);
DISPLAY 0.978723 (3450 2800);
PAINT WHITE (3450 2800);
DISPLAY INVISIBLE (3450 2800);
FORCEPROP 2 LAST SEC 1
J 0
(3450 2850);
DISPLAY 0.680851 (3450 2850);
PAINT MONO (3450 2850);
DISPLAY INVISIBLE (3450 2850);
FORCEPROP 2 LAST SEC_TYPE 0402
J 0
(3450 2850);
DISPLAY 1.021277 (3450 2850);
PAINT ORANGE (3450 2850);
DISPLAY INVISIBLE (3450 2850);
FORCEADD RES..1
(3425 2550);
FORCEPROP 1 LAST WATTAGE 1/16W
J 2
(3400 2400);
DISPLAY 0.617021 (3400 2400);
PAINT SKYBLUE (3400 2400);
FORCEPROP 1 LAST VALUE 33.2
J 2
(3400 2450);
DISPLAY 0.617021 (3400 2450);
PAINT SKYBLUE (3400 2450);
FORCEPROP 1 LAST MATERIAL CHIP
J 0
(3425 2400);
DISPLAY 0.617021 (3425 2400);
PAINT SKYBLUE (3425 2400);
FORCEPROP 1 LAST TOLERANCE 1%
J 0
(3425 2450);
DISPLAY 0.617021 (3425 2450);
PAINT SKYBLUE (3425 2450);
FORCEPROP 1 LAST LOCATION R7F23
J 0
(3375 2600);
DISPLAY 0.617021 (3375 2600);
PAINT AQUA (3375 2600);
FORCEPROP 1 LAST PART_NUMBER G21796-074
J 0
(3300 2350);
DISPLAY 0.617021 (3300 2350);
PAINT BLUE (3300 2350);
FORCEPROP 1 LAST PACK_TYPE 0402
J 0
(3675 2400);
DISPLAY 0.617021 (3675 2400);
PAINT SKYBLUE (3675 2400);
FORCEPROP 2 LAST CDS_LIB mstr_discrete
J 0
(3425 2550);
PAINT MONO (3425 2550);
DISPLAY INVISIBLE (3425 2550);
FORCEPROP 1 LASTPIN (3325 2550) $PN 1
J 0
(3337 2562);
DISPLAY 0.787234 (3337 2562);
PAINT ORANGE (3337 2562);
DISPLAY INVISIBLE (3337 2562);
FORCEPROP 1 LAST PATH I297
J 0
(3375 2700);
DISPLAY 0.978723 (3375 2700);
PAINT WHITE (3375 2700);
DISPLAY INVISIBLE (3375 2700);
FORCEPROP 2 LAST CDS_LOCATION R7F23
J 0
(3375 2600);
DISPLAY 0.617021 (3375 2600);
PAINT AQUA (3375 2600);
DISPLAY INVISIBLE (3375 2600);
FORCEPROP 2 LAST $SEC 1
J 0
(3375 2750);
PAINT MONO (3375 2750);
DISPLAY INVISIBLE (3375 2750);
FORCEPROP 2 LAST CDS_SEC 1
J 0
(3375 2750);
PAINT MONO (3375 2750);
DISPLAY INVISIBLE (3375 2750);
FORCEPROP 1 LASTPIN (3525 2550) $PN 2
J 0
(3487 2562);
DISPLAY 0.787234 (3487 2562);
PAINT ORANGE (3487 2562);
DISPLAY INVISIBLE (3487 2562);
FORCEADD RES..1
(3400 2150);
FORCEPROP 1 LAST WATTAGE 1/16W
J 2
(3375 2000);
DISPLAY 0.617021 (3375 2000);
PAINT SKYBLUE (3375 2000);
FORCEPROP 1 LAST MATERIAL CHIP
J 0
(3400 2000);
DISPLAY 0.617021 (3400 2000);
PAINT SKYBLUE (3400 2000);
FORCEPROP 1 LAST PACK_TYPE 0402
J 0
(3400 1950);
DISPLAY 0.617021 (3400 1950);
PAINT SKYBLUE (3400 1950);
FORCEPROP 1 LAST VALUE 20.0
J 2
(3375 2050);
DISPLAY 0.617021 (3375 2050);
PAINT SKYBLUE (3375 2050);
FORCEPROP 1 LAST TOLERANCE 1%
J 0
(3400 2050);
DISPLAY 0.617021 (3400 2050);
PAINT SKYBLUE (3400 2050);
FORCEPROP 1 LAST LOCATION R7F25
J 0
(3350 2200);
DISPLAY 0.617021 (3350 2200);
PAINT AQUA (3350 2200);
FORCEPROP 1 LAST PART_NUMBER G21796-173
J 0
(3350 2250);
DISPLAY 0.617021 (3350 2250);
PAINT BLUE (3350 2250);
FORCEPROP 1 LASTPIN (3300 2150) $PN 1
J 0
(3312 2162);
DISPLAY 0.787234 (3312 2162);
PAINT ORANGE (3312 2162);
DISPLAY INVISIBLE (3312 2162);
FORCEPROP 1 LASTPIN (3500 2150) $PN 2
J 0
(3462 2162);
DISPLAY 0.787234 (3462 2162);
PAINT ORANGE (3462 2162);
DISPLAY INVISIBLE (3462 2162);
FORCEPROP 2 LAST CDS_LOCATION R7F25
J 0
(3350 2200);
DISPLAY 0.617021 (3350 2200);
PAINT AQUA (3350 2200);
DISPLAY INVISIBLE (3350 2200);
FORCEPROP 2 LAST CDS_LIB mstr_discrete
J 0
(3400 2150);
PAINT ORANGE (3400 2150);
DISPLAY INVISIBLE (3400 2150);
FORCEPROP 2 LAST ROOM VDDQ_ABC_PWR_VR
J 0
(3350 2250);
DISPLAY 1.361702 (3350 2250);
PAINT ORANGE (3350 2250);
DISPLAY INVISIBLE (3350 2250);
FORCEPROP 1 LAST PATH I298
J 0
(3350 2300);
DISPLAY 0.978723 (3350 2300);
PAINT WHITE (3350 2300);
DISPLAY INVISIBLE (3350 2300);
FORCEPROP 2 LAST CDS_SEC 1
J 0
(3350 2350);
PAINT MONO (3350 2350);
DISPLAY INVISIBLE (3350 2350);
FORCEPROP 2 LAST $SEC 1
J 0
(3350 2350);
PAINT MONO (3350 2350);
DISPLAY INVISIBLE (3350 2350);
FORCEADD P3V3_STBY..1
(2950 3875);
FORCEPROP 3 LASTPIN (2950 3825) SIG_NAME P3V3_STBY\g
J 0
(2960 3835);
DISPLAY 0.659574 (2960 3835);
PAINT MONO (2960 3835);
DISPLAY INVISIBLE (2960 3835);
FORCEPROP 1 LAST HDL_POWER P3V3_STBY
J 0
(2650 3750);
DISPLAY 0.872340 (2650 3750);
PAINT ORANGE (2650 3750);
DISPLAY INVISIBLE (2650 3750);
FORCEPROP 1 LAST BODY_TYPE PLUMBING
J 0
(2905 3832);
DISPLAY 0.340426 (2905 3832);
PAINT GREEN (2905 3832);
DISPLAY INVISIBLE (2905 3832);
FORCEPROP 1 LAST VOLTAGE 3.3V
J 0
(2905 3832);
DISPLAY 0.340426 (2905 3832);
PAINT SKYBLUE (2905 3832);
DISPLAY INVISIBLE (2905 3832);
FORCEPROP 1 LAST PATH I299
J 0
(2995 3877);
DISPLAY 0.340426 (2995 3877);
PAINT GREEN (2995 3877);
DISPLAY INVISIBLE (2995 3877);
FORCEPROP 1 LAST SIZE 1B
J 0
(2995 3897);
DISPLAY 0.340426 (2995 3897);
PAINT GREEN (2995 3897);
DISPLAY INVISIBLE (2995 3897);
FORCEPROP 2 LAST CDS_LIB mstr_symbols
J 0
(2950 3875);
PAINT ORANGE (2950 3875);
DISPLAY INVISIBLE (2950 3875);
FORCEADD RES..2
(3075 3050);
FORCEPROP 1 LASTPIN (3075 2950) $PN 2
J 0
(3080 2960);
DISPLAY 0.617021 (3080 2960);
PAINT ORANGE (3080 2960);
FORCEPROP 1 LAST WATTAGE 1/16W
J 0
(3115 3025);
DISPLAY 0.617021 (3115 3025);
PAINT SKYBLUE (3115 3025);
FORCEPROP 1 LAST PACK_TYPE 0402
J 0
(3115 2875);
DISPLAY 0.617021 (3115 2875);
PAINT SKYBLUE (3115 2875);
FORCEPROP 1 LAST MATERIAL EMPTY
J 0
(3115 2975);
DISPLAY 0.617021 (3115 2975);
PAINT RED (3115 2975);
FORCEPROP 1 LAST PART_NUMBER G21796-311
J 0
(3115 2925);
DISPLAY 0.617021 (3115 2925);
PAINT BLUE (3115 2925);
FORCEPROP 1 LASTPIN (3075 3150) $PN 1
J 0
(3080 3112);
DISPLAY 0.617021 (3080 3112);
PAINT ORANGE (3080 3112);
FORCEPROP 1 LAST TOLERANCE 1.0%
J 0
(3120 3075);
DISPLAY 0.617021 (3120 3075);
PAINT SKYBLUE (3120 3075);
FORCEPROP 1 LAST LOCATION R7F36
J 0
(3120 3175);
DISPLAY 0.617021 (3120 3175);
PAINT AQUA (3120 3175);
FORCEPROP 1 LAST VALUE 2.26K
J 0
(3120 3125);
DISPLAY 0.617021 (3120 3125);
PAINT SKYBLUE (3120 3125);
FORCEPROP 2 LAST ROOM VDDQ_ABC_PWR_VR
J 0
(3125 3025);
DISPLAY 1.361702 (3125 3025);
PAINT ORANGE (3125 3025);
DISPLAY INVISIBLE (3125 3025);
FORCEPROP 2 LAST CDS_LIB mstr_discrete
J 0
(3075 3050);
PAINT ORANGE (3075 3050);
DISPLAY INVISIBLE (3075 3050);
FORCEPROP 1 LAST PATH I300
J 0
(3125 3225);
DISPLAY 0.978723 (3125 3225);
PAINT WHITE (3125 3225);
DISPLAY INVISIBLE (3125 3225);
FORCEPROP 2 LAST SEC 1
J 0
(3125 3300);
DISPLAY 0.680851 (3125 3300);
PAINT MONO (3125 3300);
DISPLAY INVISIBLE (3125 3300);
FORCEPROP 2 LAST SEC_TYPE 0402
J 0
(3125 3300);
DISPLAY 1.021277 (3125 3300);
PAINT ORANGE (3125 3300);
DISPLAY INVISIBLE (3125 3300);
FORCEADD RES..2
(2750 3200);
FORCEPROP 1 LAST PACK_TYPE 0402
J 0
(2790 3025);
DISPLAY 0.617021 (2790 3025);
PAINT SKYBLUE (2790 3025);
FORCEPROP 1 LASTPIN (2750 3100) $PN 2
J 0
(2755 3110);
DISPLAY 0.617021 (2755 3110);
PAINT ORANGE (2755 3110);
FORCEPROP 1 LASTPIN (2750 3300) $PN 1
J 0
(2755 3262);
DISPLAY 0.617021 (2755 3262);
PAINT ORANGE (2755 3262);
FORCEPROP 1 LAST WATTAGE 1/16W
J 0
(2790 3175);
DISPLAY 0.617021 (2790 3175);
PAINT SKYBLUE (2790 3175);
FORCEPROP 1 LAST MATERIAL CHIP
J 0
(2790 3125);
DISPLAY 0.617021 (2790 3125);
PAINT SKYBLUE (2790 3125);
FORCEPROP 1 LAST TOLERANCE 1%
J 0
(2795 3225);
DISPLAY 0.617021 (2795 3225);
PAINT SKYBLUE (2795 3225);
FORCEPROP 1 LAST VALUE 1.00K
J 0
(2795 3275);
DISPLAY 0.617021 (2795 3275);
PAINT SKYBLUE (2795 3275);
FORCEPROP 1 LAST LOCATION R7F22
J 0
(2795 3325);
DISPLAY 0.617021 (2795 3325);
PAINT AQUA (2795 3325);
FORCEPROP 1 LAST PART_NUMBER G21796-026
J 0
(2790 3075);
DISPLAY 0.617021 (2790 3075);
PAINT BLUE (2790 3075);
FORCEPROP 2 LAST CDS_LIB mstr_discrete
J 2
(2750 3200);
PAINT ORANGE (2750 3200);
DISPLAY INVISIBLE (2750 3200);
FORCEPROP 2 LAST CDS_LOCATION R7F22
J 0
(2795 3325);
DISPLAY 0.617021 (2795 3325);
PAINT AQUA (2795 3325);
DISPLAY INVISIBLE (2795 3325);
FORCEPROP 2 LAST SEC 1
J 0
(2800 3450);
DISPLAY 0.680851 (2800 3450);
PAINT MONO (2800 3450);
DISPLAY INVISIBLE (2800 3450);
FORCEPROP 2 LAST SEC_TYPE 0402
J 0
(2800 3450);
DISPLAY 1.021277 (2800 3450);
PAINT ORANGE (2800 3450);
DISPLAY INVISIBLE (2800 3450);
FORCEPROP 1 LAST PATH I301
J 0
(2800 3375);
DISPLAY 0.978723 (2800 3375);
PAINT WHITE (2800 3375);
DISPLAY INVISIBLE (2800 3375);
FORCEPROP 2 LAST ROOM VDDQ_ABC_PWR_VR
J 0
(2800 3375);
DISPLAY 1.361702 (2800 3375);
PAINT ORANGE (2800 3375);
DISPLAY INVISIBLE (2800 3375);
FORCEADD RES..1
(2925 2500);
FORCEPROP 1 LAST WATTAGE 1/16W
J 2
(2825 2450);
DISPLAY 0.617021 (2825 2450);
PAINT SKYBLUE (2825 2450);
FORCEPROP 1 LAST VALUE 0.0
J 2
(2900 2450);
DISPLAY 0.617021 (2900 2450);
PAINT SKYBLUE (2900 2450);
FORCEPROP 1 LAST PART_NUMBER G21497-005
J 0
(2775 2400);
DISPLAY 0.617021 (2775 2400);
PAINT BLUE (2775 2400);
FORCEPROP 1 LASTPIN (2825 2500) $PN 1
J 0
(2837 2512);
DISPLAY 0.617021 (2837 2512);
PAINT ORANGE (2837 2512);
FORCEPROP 1 LAST TOLERANCE 5%
J 0
(2925 2450);
DISPLAY 0.617021 (2925 2450);
PAINT SKYBLUE (2925 2450);
FORCEPROP 1 LASTPIN (3025 2500) $PN 2
J 0
(2987 2512);
DISPLAY 0.617021 (2987 2512);
PAINT ORANGE (2987 2512);
FORCEPROP 1 LAST LOCATION R7G4
J 0
(2950 2550);
DISPLAY 0.617021 (2950 2550);
PAINT AQUA (2950 2550);
FORCEPROP 1 LAST PACK_TYPE 0402
J 0
(3025 2450);
DISPLAY 0.617021 (3025 2450);
PAINT SKYBLUE (3025 2450);
FORCEPROP 1 LAST MATERIAL CHIP
J 0
(3150 2450);
DISPLAY 0.617021 (3150 2450);
PAINT SKYBLUE (3150 2450);
FORCEPROP 2 LAST CDS_LIB mstr_discrete
J 0
(2925 2500);
PAINT ORANGE (2925 2500);
DISPLAY INVISIBLE (2925 2500);
FORCEPROP 2 LAST CDS_LOCATION R7G4
J 0
(2950 2550);
DISPLAY 0.617021 (2950 2550);
PAINT AQUA (2950 2550);
DISPLAY INVISIBLE (2950 2550);
FORCEPROP 2 LAST ROOM VDDQ_ABC_PWR_VR
J 0
(2875 2600);
DISPLAY 1.361702 (2875 2600);
PAINT ORANGE (2875 2600);
DISPLAY INVISIBLE (2875 2600);
FORCEPROP 1 LAST PATH I302
J 0
(2875 2650);
DISPLAY 0.978723 (2875 2650);
PAINT WHITE (2875 2650);
DISPLAY INVISIBLE (2875 2650);
FORCEPROP 2 LAST SEC 1
J 0
(2875 2725);
DISPLAY 0.680851 (2875 2725);
PAINT MONO (2875 2725);
DISPLAY INVISIBLE (2875 2725);
FORCEPROP 2 LAST SEC_TYPE 0402
J 0
(2875 2725);
DISPLAY 1.021277 (2875 2725);
PAINT ORANGE (2875 2725);
DISPLAY INVISIBLE (2875 2725);
FORCEADD RES..2
(2400 3200);
FORCEPROP 1 LAST PACK_TYPE 0402
J 0
(2440 3025);
DISPLAY 0.617021 (2440 3025);
PAINT SKYBLUE (2440 3025);
FORCEPROP 1 LASTPIN (2400 3100) $PN 2
J 0
(2405 3110);
DISPLAY 0.617021 (2405 3110);
PAINT ORANGE (2405 3110);
FORCEPROP 1 LASTPIN (2400 3300) $PN 1
J 0
(2405 3262);
DISPLAY 0.617021 (2405 3262);
PAINT ORANGE (2405 3262);
FORCEPROP 1 LAST TOLERANCE 1%
J 0
(2445 3225);
DISPLAY 0.617021 (2445 3225);
PAINT SKYBLUE (2445 3225);
FORCEPROP 1 LAST MATERIAL CHIP
J 0
(2440 3125);
DISPLAY 0.617021 (2440 3125);
PAINT SKYBLUE (2440 3125);
FORCEPROP 1 LAST WATTAGE 1/16W
J 0
(2440 3175);
DISPLAY 0.617021 (2440 3175);
PAINT SKYBLUE (2440 3175);
FORCEPROP 1 LAST VALUE 1.00K
J 0
(2445 3275);
DISPLAY 0.617021 (2445 3275);
PAINT SKYBLUE (2445 3275);
FORCEPROP 1 LAST PART_NUMBER G21796-026
J 0
(2440 3075);
DISPLAY 0.617021 (2440 3075);
PAINT BLUE (2440 3075);
FORCEPROP 1 LAST LOCATION R7F27
J 0
(2445 3325);
DISPLAY 0.617021 (2445 3325);
PAINT AQUA (2445 3325);
FORCEPROP 2 LAST CDS_LIB mstr_discrete
J 0
(2400 3200);
PAINT ORANGE (2400 3200);
DISPLAY INVISIBLE (2400 3200);
FORCEPROP 2 LAST CDS_LOCATION R7F27
J 0
(2445 3325);
DISPLAY 0.617021 (2445 3325);
PAINT AQUA (2445 3325);
DISPLAY INVISIBLE (2445 3325);
FORCEPROP 2 LAST SEC_TYPE 0402
J 0
(2450 3425);
DISPLAY 1.021277 (2450 3425);
PAINT ORANGE (2450 3425);
DISPLAY INVISIBLE (2450 3425);
FORCEPROP 2 LAST SEC 1
J 0
(2450 3425);
DISPLAY 0.680851 (2450 3425);
PAINT MONO (2450 3425);
DISPLAY INVISIBLE (2450 3425);
FORCEPROP 1 LAST PATH I303
J 0
(2450 3375);
DISPLAY 0.978723 (2450 3375);
PAINT WHITE (2450 3375);
DISPLAY INVISIBLE (2450 3375);
FORCEPROP 0 LAST ROOM VDDQ_ABC_PWR_VR
J 0
(2450 3425);
DISPLAY 1.021277 (2450 3425);
PAINT ORANGE (2450 3425);
DISPLAY INVISIBLE (2450 3425);
FORCEADD RES..1
(3075 2100);
FORCEPROP 1 LAST WATTAGE 1/16W
J 2
(3050 1950);
DISPLAY 0.617021 (3050 1950);
PAINT SKYBLUE (3050 1950);
FORCEPROP 1 LAST VALUE 20.0
J 2
(3050 2000);
DISPLAY 0.617021 (3050 2000);
PAINT SKYBLUE (3050 2000);
FORCEPROP 1 LAST MATERIAL CHIP
J 0
(3075 1950);
DISPLAY 0.617021 (3075 1950);
PAINT SKYBLUE (3075 1950);
FORCEPROP 1 LAST PACK_TYPE 0402
J 0
(3075 1900);
DISPLAY 0.617021 (3075 1900);
PAINT SKYBLUE (3075 1900);
FORCEPROP 1 LAST TOLERANCE 1%
J 0
(3075 2000);
DISPLAY 0.617021 (3075 2000);
PAINT SKYBLUE (3075 2000);
FORCEPROP 1 LAST PART_NUMBER G21796-173
J 0
(3025 2200);
DISPLAY 0.617021 (3025 2200);
PAINT BLUE (3025 2200);
FORCEPROP 1 LAST LOCATION R7F26
J 0
(3025 2150);
DISPLAY 0.617021 (3025 2150);
PAINT AQUA (3025 2150);
FORCEPROP 1 LASTPIN (2975 2100) $PN 1
J 0
(2987 2112);
DISPLAY 0.787234 (2987 2112);
PAINT ORANGE (2987 2112);
DISPLAY INVISIBLE (2987 2112);
FORCEPROP 2 LAST ROOM VDDQ_ABC_PWR_VR
J 0
(3025 2200);
DISPLAY 1.361702 (3025 2200);
PAINT ORANGE (3025 2200);
DISPLAY INVISIBLE (3025 2200);
FORCEPROP 1 LAST PATH I304
J 0
(3025 2250);
DISPLAY 0.978723 (3025 2250);
PAINT WHITE (3025 2250);
DISPLAY INVISIBLE (3025 2250);
FORCEPROP 2 LAST CDS_LOCATION R7F26
J 0
(3025 2150);
DISPLAY 0.617021 (3025 2150);
PAINT AQUA (3025 2150);
DISPLAY INVISIBLE (3025 2150);
FORCEPROP 2 LAST $SEC 1
J 0
(3025 2300);
PAINT MONO (3025 2300);
DISPLAY INVISIBLE (3025 2300);
FORCEPROP 2 LAST CDS_SEC 1
J 0
(3025 2300);
PAINT MONO (3025 2300);
DISPLAY INVISIBLE (3025 2300);
FORCEPROP 2 LAST CDS_LIB mstr_discrete
J 0
(3075 2100);
PAINT ORANGE (3075 2100);
DISPLAY INVISIBLE (3075 2100);
FORCEPROP 1 LASTPIN (3175 2100) $PN 2
J 0
(3137 2112);
DISPLAY 0.787234 (3137 2112);
PAINT ORANGE (3137 2112);
DISPLAY INVISIBLE (3137 2112);
FORCEADD CAP..1
(3225 1350);
FORCEPROP 1 LASTPIN (3225 1250) $PN 2
J 0
(3235 1230);
DISPLAY 0.617021 (3235 1230);
PAINT ORANGE (3235 1230);
FORCEPROP 1 LASTPIN (3225 1450) $PN 1
J 0
(3235 1430);
DISPLAY 0.617021 (3235 1430);
PAINT ORANGE (3235 1430);
FORCEPROP 1 LAST MATERIAL X7R
J 0
(3275 1250);
DISPLAY 0.617021 (3275 1250);
PAINT SKYBLUE (3275 1250);
FORCEPROP 1 LAST VOLTAGE 50V
J 0
(3275 1350);
DISPLAY 0.617021 (3275 1350);
PAINT SKYBLUE (3275 1350);
FORCEPROP 1 LAST PACK_TYPE 0402LF
J 0
(3275 1150);
DISPLAY 0.617021 (3275 1150);
PAINT SKYBLUE (3275 1150);
FORCEPROP 1 LAST TOLERANCE 10%
J 0
(3275 1300);
DISPLAY 0.617021 (3275 1300);
PAINT SKYBLUE (3275 1300);
FORCEPROP 1 LAST VALUE 1000PF
J 0
(3275 1400);
DISPLAY 0.617021 (3275 1400);
PAINT SKYBLUE (3275 1400);
FORCEPROP 1 LAST PART_NUMBER A36096-046
J 0
(3275 1200);
DISPLAY 0.617021 (3275 1200);
PAINT BLUE (3275 1200);
FORCEPROP 1 LAST LOCATION C7F14
J 0
(3275 1450);
DISPLAY 0.617021 (3275 1450);
PAINT AQUA (3275 1450);
FORCEPROP 2 LAST CDS_LOCATION C7F14
J 0
(3275 1450);
DISPLAY 0.617021 (3275 1450);
PAINT AQUA (3275 1450);
DISPLAY INVISIBLE (3275 1450);
FORCEPROP 2 LAST CDS_LIB mstr_discrete
J 0
(3225 1350);
PAINT MONO (3225 1350);
DISPLAY INVISIBLE (3225 1350);
FORCEPROP 1 LAST PATH I305
J 0
(3275 1500);
DISPLAY 0.978723 (3275 1500);
PAINT WHITE (3275 1500);
DISPLAY INVISIBLE (3275 1500);
FORCEPROP 0 LAST ROOM VDDQ_ABC_PWR_VR
J 0
(3275 1550);
DISPLAY 1.021277 (3275 1550);
PAINT ORANGE (3275 1550);
DISPLAY INVISIBLE (3275 1550);
FORCEPROP 2 LAST SEC 1
J 0
(3275 1550);
DISPLAY 0.680851 (3275 1550);
PAINT MONO (3275 1550);
DISPLAY INVISIBLE (3275 1550);
FORCEPROP 2 LAST SEC_TYPE 0402LF
J 0
(3275 1550);
DISPLAY 1.021277 (3275 1550);
PAINT ORANGE (3275 1550);
DISPLAY INVISIBLE (3275 1550);
FORCEADD GND..1
(3225 1075);
FORCEPROP 3 LASTPIN (3225 1125) SIG_NAME GND\g
J 0
(3235 1135);
DISPLAY 0.659574 (3235 1135);
PAINT MONO (3235 1135);
DISPLAY INVISIBLE (3235 1135);
FORCEPROP 2 LAST ROOM VDDQ_ABC_PWR_VR
J 0
(2650 1150);
DISPLAY 1.361702 (2650 1150);
PAINT ORANGE (2650 1150);
DISPLAY INVISIBLE (2650 1150);
FORCEPROP 1 LAST BODY_TYPE PLUMBING
J 0
(3180 1032);
DISPLAY 0.340426 (3180 1032);
PAINT GREEN (3180 1032);
DISPLAY INVISIBLE (3180 1032);
FORCEPROP 1 LAST PATH I306
J 0
(3300 1075);
DISPLAY 0.872340 (3300 1075);
PAINT AQUA (3300 1075);
DISPLAY INVISIBLE (3300 1075);
FORCEPROP 2 LAST CDS_LIB mstr_symbols
J 0
(3225 1075);
PAINT MONO (3225 1075);
DISPLAY INVISIBLE (3225 1075);
FORCEPROP 1 LAST SIZE 1B
J 0
(3300 1025);
DISPLAY 1.170213 (3300 1025);
PAINT AQUA (3300 1025);
DISPLAY INVISIBLE (3300 1025);
FORCEPROP 1 LAST VOLTAGE 0
J 0
(3225 1075);
PAINT SKYBLUE (3225 1075);
DISPLAY INVISIBLE (3225 1075);
FORCEPROP 1 LAST HDL_POWER GND
J 0
(3225 1225);
DISPLAY 1.170213 (3225 1225);
PAINT GREEN (3225 1225);
DISPLAY INVISIBLE (3225 1225);
FORCEADD RES..1
(3075 1800);
FORCEPROP 1 LAST WATTAGE 1/16W
J 2
(3050 1650);
DISPLAY 0.617021 (3050 1650);
PAINT SKYBLUE (3050 1650);
FORCEPROP 1 LAST VALUE 0.0
J 2
(2975 1700);
DISPLAY 0.617021 (2975 1700);
PAINT SKYBLUE (2975 1700);
FORCEPROP 1 LASTPIN (2975 1800) $PN 1
J 0
(2987 1812);
DISPLAY 0.617021 (2987 1812);
PAINT ORANGE (2987 1812);
FORCEPROP 1 LAST TOLERANCE 5%
J 0
(3025 1700);
DISPLAY 0.617021 (3025 1700);
PAINT SKYBLUE (3025 1700);
FORCEPROP 1 LAST PART_NUMBER G21497-005
J 0
(2925 1750);
DISPLAY 0.617021 (2925 1750);
PAINT BLUE (2925 1750);
FORCEPROP 1 LAST LOCATION R7G2
J 0
(3025 1850);
DISPLAY 0.617021 (3025 1850);
PAINT AQUA (3025 1850);
FORCEPROP 1 LAST MATERIAL CHIP
J 0
(3075 1650);
DISPLAY 0.617021 (3075 1650);
PAINT SKYBLUE (3075 1650);
FORCEPROP 1 LAST PACK_TYPE 0402
J 0
(3150 1700);
DISPLAY 0.617021 (3150 1700);
PAINT SKYBLUE (3150 1700);
FORCEPROP 1 LASTPIN (3175 1800) $PN 2
J 0
(3137 1812);
DISPLAY 0.617021 (3137 1812);
PAINT ORANGE (3137 1812);
FORCEPROP 2 LAST SEC_TYPE 0402
J 0
(3025 2000);
DISPLAY 1.021277 (3025 2000);
PAINT ORANGE (3025 2000);
DISPLAY INVISIBLE (3025 2000);
FORCEPROP 2 LAST SEC 1
J 0
(3025 2000);
DISPLAY 0.680851 (3025 2000);
PAINT MONO (3025 2000);
DISPLAY INVISIBLE (3025 2000);
FORCEPROP 2 LAST CDS_LOCATION R7G2
J 0
(3025 1850);
DISPLAY 0.617021 (3025 1850);
PAINT AQUA (3025 1850);
DISPLAY INVISIBLE (3025 1850);
FORCEPROP 1 LAST PATH I307
J 0
(3025 1950);
DISPLAY 0.978723 (3025 1950);
PAINT WHITE (3025 1950);
DISPLAY INVISIBLE (3025 1950);
FORCEPROP 2 LAST ROOM VDDQ_ABC_PWR_VR
J 0
(3025 1900);
DISPLAY 1.361702 (3025 1900);
PAINT ORANGE (3025 1900);
DISPLAY INVISIBLE (3025 1900);
FORCEPROP 2 LAST CDS_LIB mstr_discrete
J 0
(3075 1800);
PAINT ORANGE (3075 1800);
DISPLAY INVISIBLE (3075 1800);
FORCEADD GND..1
(2300 925);
FORCEPROP 3 LASTPIN (2300 975) SIG_NAME GND\g
J 0
(2310 985);
DISPLAY 0.659574 (2310 985);
PAINT MONO (2310 985);
DISPLAY INVISIBLE (2310 985);
FORCEPROP 2 LAST ROOM VDDQ_ABC_PWR_VR
J 0
(1725 1000);
DISPLAY 1.361702 (1725 1000);
PAINT ORANGE (1725 1000);
DISPLAY INVISIBLE (1725 1000);
FORCEPROP 1 LAST PATH I308
J 0
(2375 925);
DISPLAY 0.872340 (2375 925);
PAINT AQUA (2375 925);
DISPLAY INVISIBLE (2375 925);
FORCEPROP 1 LAST BODY_TYPE PLUMBING
J 0
(2255 882);
DISPLAY 0.340426 (2255 882);
PAINT GREEN (2255 882);
DISPLAY INVISIBLE (2255 882);
FORCEPROP 2 LAST CDS_LIB mstr_symbols
J 0
(2300 925);
PAINT ORANGE (2300 925);
DISPLAY INVISIBLE (2300 925);
FORCEPROP 1 LAST SIZE 1B
J 0
(2375 875);
DISPLAY 1.170213 (2375 875);
PAINT AQUA (2375 875);
DISPLAY INVISIBLE (2375 875);
FORCEPROP 1 LAST VOLTAGE 0
J 0
(2300 925);
PAINT SKYBLUE (2300 925);
DISPLAY INVISIBLE (2300 925);
FORCEPROP 1 LAST HDL_POWER GND
J 0
(2300 1075);
DISPLAY 1.170213 (2300 1075);
PAINT GREEN (2300 1075);
DISPLAY INVISIBLE (2300 1075);
FORCEADD CAP_A..1
(1825 3200);
FORCEPROP 1 LAST PACK_TYPE 0402V
J 0
(1875 3000);
DISPLAY 0.617021 (1875 3000);
PAINT SKYBLUE (1875 3000);
FORCEPROP 1 LAST LOCATION C7F18
J 0
(1875 3300);
DISPLAY 0.617021 (1875 3300);
PAINT AQUA (1875 3300);
FORCEPROP 1 LAST VALUE 1.0UF
J 0
(1875 3250);
DISPLAY 0.617021 (1875 3250);
PAINT SKYBLUE (1875 3250);
FORCEPROP 1 LAST TOLERANCE 10%
J 0
(1875 3150);
DISPLAY 0.617021 (1875 3150);
PAINT SKYBLUE (1875 3150);
FORCEPROP 1 LAST MATERIAL X6S
J 0
(1875 3100);
DISPLAY 0.617021 (1875 3100);
PAINT SKYBLUE (1875 3100);
FORCEPROP 1 LAST VOLTAGE 6.3V
J 0
(1875 3200);
DISPLAY 0.617021 (1875 3200);
PAINT SKYBLUE (1875 3200);
FORCEPROP 1 LAST PART_NUMBER D97712-004
J 0
(1875 3050);
DISPLAY 0.617021 (1875 3050);
PAINT BLUE (1875 3050);
FORCEPROP 2 LAST CDS_LIB dev_discrete
J 0
(1825 3200);
PAINT ORANGE (1825 3200);
DISPLAY INVISIBLE (1825 3200);
FORCEPROP 2 LAST CDS_LOCATION C7F18
J 0
(1875 3300);
DISPLAY 0.617021 (1875 3300);
PAINT AQUA (1875 3300);
DISPLAY INVISIBLE (1875 3300);
FORCEPROP 1 LASTPIN (1825 3300) $PN 1
J 0
(1835 3280);
DISPLAY 0.787234 (1835 3280);
PAINT ORANGE (1835 3280);
DISPLAY INVISIBLE (1835 3280);
FORCEPROP 1 LASTPIN (1825 3100) $PN 2
J 0
(1835 3080);
DISPLAY 0.787234 (1835 3080);
PAINT ORANGE (1835 3080);
DISPLAY INVISIBLE (1835 3080);
FORCEPROP 1 LAST PATH I309
J 0
(1875 3350);
DISPLAY 0.978723 (1875 3350);
PAINT WHITE (1875 3350);
DISPLAY INVISIBLE (1875 3350);
FORCEPROP 2 LAST $SEC 1
J 0
(1875 3400);
DISPLAY 0.680851 (1875 3400);
PAINT MONO (1875 3400);
DISPLAY INVISIBLE (1875 3400);
FORCEPROP 2 LAST CDS_SEC 1
J 0
(1875 3400);
DISPLAY 1.021277 (1875 3400);
PAINT ORANGE (1875 3400);
DISPLAY INVISIBLE (1875 3400);
FORCEPROP 2 LAST ROOM VDDQ_ABC_PWR_VR
J 0
(1875 3350);
DISPLAY 1.361702 (1875 3350);
PAINT ORANGE (1875 3350);
DISPLAY INVISIBLE (1875 3350);
FORCEADD GND..1
(1825 3000);
FORCEPROP 3 LASTPIN (1825 3050) SIG_NAME GND\g
J 0
(1835 3060);
DISPLAY 0.659574 (1835 3060);
PAINT MONO (1835 3060);
DISPLAY INVISIBLE (1835 3060);
FORCEPROP 1 LAST VOLTAGE 0
J 0
(1825 3000);
PAINT SKYBLUE (1825 3000);
DISPLAY INVISIBLE (1825 3000);
FORCEPROP 1 LAST SIZE 1B
J 0
(1900 2950);
DISPLAY 1.170213 (1900 2950);
PAINT AQUA (1900 2950);
DISPLAY INVISIBLE (1900 2950);
FORCEPROP 2 LAST CDS_LIB mstr_symbols
J 0
(1825 3000);
PAINT ORANGE (1825 3000);
DISPLAY INVISIBLE (1825 3000);
FORCEPROP 1 LAST BODY_TYPE PLUMBING
J 0
(1780 2957);
DISPLAY 0.340426 (1780 2957);
PAINT GREEN (1780 2957);
DISPLAY INVISIBLE (1780 2957);
FORCEPROP 1 LAST PATH I310
J 0
(1900 3000);
DISPLAY 0.872340 (1900 3000);
PAINT AQUA (1900 3000);
DISPLAY INVISIBLE (1900 3000);
FORCEPROP 2 LAST ROOM VDDQ_ABC_PWR_VR
J 0
(1250 3075);
DISPLAY 1.361702 (1250 3075);
PAINT ORANGE (1250 3075);
DISPLAY INVISIBLE (1250 3075);
FORCEPROP 1 LAST HDL_POWER GND
J 0
(1825 3150);
DISPLAY 1.170213 (1825 3150);
PAINT GREEN (1825 3150);
DISPLAY INVISIBLE (1825 3150);
FORCEADD CAP_A..1
(1425 3200);
FORCEPROP 1 LAST PACK_TYPE 0402V
J 0
(1475 3000);
DISPLAY 0.617021 (1475 3000);
PAINT SKYBLUE (1475 3000);
FORCEPROP 1 LAST PART_NUMBER A36096-030
J 0
(1475 3050);
DISPLAY 0.617021 (1475 3050);
PAINT BLUE (1475 3050);
FORCEPROP 1 LASTPIN (1425 3100) $PN 2
J 0
(1435 3080);
DISPLAY 0.617021 (1435 3080);
PAINT ORANGE (1435 3080);
FORCEPROP 1 LASTPIN (1425 3300) $PN 1
J 0
(1435 3280);
DISPLAY 0.617021 (1435 3280);
PAINT ORANGE (1435 3280);
FORCEPROP 1 LAST MATERIAL X7R
J 0
(1475 3100);
DISPLAY 0.617021 (1475 3100);
PAINT SKYBLUE (1475 3100);
FORCEPROP 1 LAST VOLTAGE 16V
J 0
(1475 3200);
DISPLAY 0.617021 (1475 3200);
PAINT SKYBLUE (1475 3200);
FORCEPROP 1 LAST TOLERANCE 10%
J 0
(1475 3150);
DISPLAY 0.617021 (1475 3150);
PAINT SKYBLUE (1475 3150);
FORCEPROP 1 LAST VALUE 0.1UF
J 0
(1475 3250);
DISPLAY 0.617021 (1475 3250);
PAINT SKYBLUE (1475 3250);
FORCEPROP 1 LAST LOCATION C7F17
J 0
(1475 3300);
DISPLAY 0.617021 (1475 3300);
PAINT AQUA (1475 3300);
FORCEPROP 2 LAST CDS_LOCATION C7F17
J 0
(1475 3300);
DISPLAY 0.617021 (1475 3300);
PAINT AQUA (1475 3300);
DISPLAY INVISIBLE (1475 3300);
FORCEPROP 2 LAST CDS_LIB dev_discrete
J 0
(1425 3200);
PAINT ORANGE (1425 3200);
DISPLAY INVISIBLE (1425 3200);
FORCEPROP 1 LAST PATH I311
J 0
(1475 3350);
DISPLAY 0.978723 (1475 3350);
PAINT WHITE (1475 3350);
DISPLAY INVISIBLE (1475 3350);
FORCEPROP 2 LAST ROOM VDDQ_ABC_PWR_VR
J 0
(1475 3350);
DISPLAY 1.361702 (1475 3350);
PAINT ORANGE (1475 3350);
DISPLAY INVISIBLE (1475 3350);
FORCEPROP 2 LAST CDS_SEC 1
J 0
(1475 3350);
PAINT ORANGE (1475 3350);
DISPLAY INVISIBLE (1475 3350);
FORCEPROP 2 LAST SEC_TYPE 0402V
J 0
(1475 3425);
DISPLAY 1.021277 (1475 3425);
PAINT ORANGE (1475 3425);
DISPLAY INVISIBLE (1475 3425);
FORCEPROP 2 LAST SEC 1
J 0
(1475 3425);
DISPLAY 0.680851 (1475 3425);
PAINT MONO (1475 3425);
DISPLAY INVISIBLE (1475 3425);
FORCEADD GND..1
(1425 3000);
FORCEPROP 3 LASTPIN (1425 3050) SIG_NAME GND\g
J 0
(1435 3060);
DISPLAY 0.659574 (1435 3060);
PAINT MONO (1435 3060);
DISPLAY INVISIBLE (1435 3060);
FORCEPROP 2 LAST ROOM VDDQ_ABC_PWR_VR
J 0
(850 3075);
DISPLAY 1.361702 (850 3075);
PAINT ORANGE (850 3075);
DISPLAY INVISIBLE (850 3075);
FORCEPROP 1 LAST BODY_TYPE PLUMBING
J 0
(1380 2957);
DISPLAY 0.340426 (1380 2957);
PAINT GREEN (1380 2957);
DISPLAY INVISIBLE (1380 2957);
FORCEPROP 1 LAST PATH I312
J 0
(1500 3000);
DISPLAY 0.872340 (1500 3000);
PAINT AQUA (1500 3000);
DISPLAY INVISIBLE (1500 3000);
FORCEPROP 2 LAST CDS_LIB mstr_symbols
J 0
(1425 3000);
PAINT ORANGE (1425 3000);
DISPLAY INVISIBLE (1425 3000);
FORCEPROP 1 LAST SIZE 1B
J 0
(1500 2950);
DISPLAY 1.170213 (1500 2950);
PAINT AQUA (1500 2950);
DISPLAY INVISIBLE (1500 2950);
FORCEPROP 1 LAST VOLTAGE 0
J 0
(1425 3000);
PAINT SKYBLUE (1425 3000);
DISPLAY INVISIBLE (1425 3000);
FORCEPROP 1 LAST HDL_POWER GND
J 0
(1425 3150);
DISPLAY 1.170213 (1425 3150);
PAINT GREEN (1425 3150);
DISPLAY INVISIBLE (1425 3150);
FORCEADD RES..2
(1125 3550);
FORCEPROP 1 LASTPIN (1125 3450) $PN 2
J 0
(1130 3460);
DISPLAY 0.617021 (1130 3460);
PAINT ORANGE (1130 3460);
FORCEPROP 1 LAST WATTAGE 1/16W
J 0
(1165 3525);
DISPLAY 0.617021 (1165 3525);
PAINT SKYBLUE (1165 3525);
FORCEPROP 1 LAST MATERIAL CHIP
J 0
(1165 3475);
DISPLAY 0.617021 (1165 3475);
PAINT SKYBLUE (1165 3475);
FORCEPROP 1 LAST PACK_TYPE 0402
J 0
(1165 3375);
DISPLAY 0.617021 (1165 3375);
PAINT SKYBLUE (1165 3375);
FORCEPROP 1 LAST PART_NUMBER G21497-005
J 0
(1165 3425);
DISPLAY 0.617021 (1165 3425);
PAINT BLUE (1165 3425);
FORCEPROP 1 LAST TOLERANCE 5%
J 0
(1170 3575);
DISPLAY 0.617021 (1170 3575);
PAINT SKYBLUE (1170 3575);
FORCEPROP 1 LAST VALUE 0.0
J 0
(1170 3625);
DISPLAY 0.617021 (1170 3625);
PAINT SKYBLUE (1170 3625);
FORCEPROP 1 LASTPIN (1125 3650) $PN 1
J 0
(1130 3612);
DISPLAY 0.617021 (1130 3612);
PAINT ORANGE (1130 3612);
FORCEPROP 1 LAST LOCATION R3T13
J 0
(1170 3675);
DISPLAY 0.617021 (1170 3675);
PAINT AQUA (1170 3675);
FORCEPROP 2 LAST CDS_LIB mstr_discrete
J 0
(1125 3550);
PAINT ORANGE (1125 3550);
DISPLAY INVISIBLE (1125 3550);
FORCEPROP 2 LAST ROOM VDDQ_ABC_PWR_VR
J 0
(1175 3725);
DISPLAY 1.361702 (1175 3725);
PAINT ORANGE (1175 3725);
DISPLAY INVISIBLE (1175 3725);
FORCEPROP 1 LAST PATH I313
J 0
(1175 3725);
DISPLAY 0.978723 (1175 3725);
PAINT WHITE (1175 3725);
DISPLAY INVISIBLE (1175 3725);
FORCEPROP 2 LAST CDS_LOCATION R3T13
J 0
(1170 3675);
DISPLAY 0.617021 (1170 3675);
PAINT AQUA (1170 3675);
DISPLAY INVISIBLE (1170 3675);
FORCEPROP 2 LAST SEC 1
J 0
(1175 3800);
DISPLAY 0.680851 (1175 3800);
PAINT MONO (1175 3800);
DISPLAY INVISIBLE (1175 3800);
FORCEPROP 2 LAST SEC_TYPE 0402
J 0
(1175 3800);
DISPLAY 1.021277 (1175 3800);
PAINT ORANGE (1175 3800);
DISPLAY INVISIBLE (1175 3800);
FORCEADD P3V3_STBY..1
(1125 3975);
FORCEPROP 3 LASTPIN (1125 3925) SIG_NAME P3V3_STBY\g
J 0
(1135 3935);
DISPLAY 0.659574 (1135 3935);
PAINT MONO (1135 3935);
DISPLAY INVISIBLE (1135 3935);
FORCEPROP 1 LAST HDL_POWER P3V3_STBY
J 0
(825 3850);
DISPLAY 0.872340 (825 3850);
PAINT ORANGE (825 3850);
DISPLAY INVISIBLE (825 3850);
FORCEPROP 1 LAST BODY_TYPE PLUMBING
J 0
(1080 3932);
DISPLAY 0.340426 (1080 3932);
PAINT GREEN (1080 3932);
DISPLAY INVISIBLE (1080 3932);
FORCEPROP 1 LAST VOLTAGE 3.3V
J 0
(1080 3932);
DISPLAY 0.340426 (1080 3932);
PAINT SKYBLUE (1080 3932);
DISPLAY INVISIBLE (1080 3932);
FORCEPROP 2 LAST CDS_LIB mstr_symbols
J 0
(1125 3975);
PAINT ORANGE (1125 3975);
DISPLAY INVISIBLE (1125 3975);
FORCEPROP 1 LAST SIZE 1B
J 0
(1170 3997);
DISPLAY 0.340426 (1170 3997);
PAINT GREEN (1170 3997);
DISPLAY INVISIBLE (1170 3997);
FORCEPROP 1 LAST PATH I314
J 0
(1170 3977);
DISPLAY 0.340426 (1170 3977);
PAINT GREEN (1170 3977);
DISPLAY INVISIBLE (1170 3977);
FORCEADD RES..2
(425 3625);
FORCEPROP 1 LAST WATTAGE 1/16W
J 0
(465 3600);
DISPLAY 0.617021 (465 3600);
PAINT SKYBLUE (465 3600);
FORCEPROP 1 LAST PACK_TYPE 0402
J 0
(465 3450);
DISPLAY 0.617021 (465 3450);
PAINT SKYBLUE (465 3450);
FORCEPROP 1 LAST TOLERANCE 1%
J 0
(470 3650);
DISPLAY 0.617021 (470 3650);
PAINT SKYBLUE (470 3650);
FORCEPROP 1 LAST VALUE 100.0K
J 0
(470 3700);
DISPLAY 0.617021 (470 3700);
PAINT SKYBLUE (470 3700);
FORCEPROP 1 LAST PART_NUMBER G21796-010
J 0
(465 3500);
DISPLAY 0.617021 (465 3500);
PAINT BLUE (465 3500);
FORCEPROP 1 LAST LOCATION R7F20
J 0
(470 3750);
DISPLAY 0.617021 (470 3750);
PAINT AQUA (470 3750);
FORCEPROP 1 LAST MATERIAL EMPTY
J 0
(465 3550);
DISPLAY 0.617021 (465 3550);
PAINT RED (465 3550);
FORCEPROP 1 LASTPIN (425 3525) $PN 2
J 0
(430 3535);
DISPLAY 0.787234 (430 3535);
PAINT ORANGE (430 3535);
DISPLAY INVISIBLE (430 3535);
FORCEPROP 2 LAST CDS_LIB mstr_discrete
J 0
(425 3625);
PAINT ORANGE (425 3625);
DISPLAY INVISIBLE (425 3625);
FORCEPROP 1 LASTPIN (425 3725) $PN 1
J 0
(430 3687);
DISPLAY 0.787234 (430 3687);
PAINT ORANGE (430 3687);
DISPLAY INVISIBLE (430 3687);
FORCEPROP 2 LAST CDS_LOCATION R7F20
J 0
(470 3750);
DISPLAY 0.617021 (470 3750);
PAINT AQUA (470 3750);
DISPLAY INVISIBLE (470 3750);
FORCEPROP 1 LAST PATH I315
J 0
(475 3800);
DISPLAY 0.978723 (475 3800);
PAINT WHITE (475 3800);
DISPLAY INVISIBLE (475 3800);
FORCEPROP 0 LAST ROOM BMC
J 0
(475 3850);
DISPLAY 0.617021 (475 3850);
PAINT ORANGE (475 3850);
DISPLAY INVISIBLE (475 3850);
FORCEPROP 2 LAST $SEC 1
J 0
(475 3850);
PAINT MONO (475 3850);
DISPLAY INVISIBLE (475 3850);
FORCEPROP 2 LAST CDS_SEC 1
J 0
(475 3850);
PAINT MONO (475 3850);
DISPLAY INVISIBLE (475 3850);
FORCEPROP 0 LAST BOM_COST SM_CONTROLLER
J 0
(475 3950);
DISPLAY 1.021277 (475 3950);
PAINT ORANGE (475 3950);
DISPLAY INVISIBLE (475 3950);
FORCEADD RES..2
(850 400);
FORCEPROP 1 LAST PACK_TYPE 0402
J 0
(890 225);
DISPLAY 0.617021 (890 225);
PAINT SKYBLUE (890 225);
FORCEPROP 1 LAST MATERIAL CHIP
J 0
(890 325);
DISPLAY 0.617021 (890 325);
PAINT SKYBLUE (890 325);
FORCEPROP 1 LAST TOLERANCE 1%
J 0
(895 425);
DISPLAY 0.617021 (895 425);
PAINT SKYBLUE (895 425);
FORCEPROP 1 LAST WATTAGE 1/16W
J 0
(890 375);
DISPLAY 0.617021 (890 375);
PAINT SKYBLUE (890 375);
FORCEPROP 1 LAST VALUE 8.06K
J 0
(895 475);
DISPLAY 0.617021 (895 475);
PAINT SKYBLUE (895 475);
FORCEPROP 1 LAST PART_NUMBER G21796-078
J 0
(890 275);
DISPLAY 0.617021 (890 275);
PAINT BLUE (890 275);
FORCEPROP 1 LAST LOCATION R7G10
J 0
(895 525);
DISPLAY 0.617021 (895 525);
PAINT AQUA (895 525);
FORCEPROP 1 LASTPIN (850 300) $PN 2
J 0
(855 310);
DISPLAY 0.787234 (855 310);
PAINT ORANGE (855 310);
DISPLAY INVISIBLE (855 310);
FORCEPROP 1 LASTPIN (850 500) $PN 1
J 0
(855 462);
DISPLAY 0.787234 (855 462);
PAINT ORANGE (855 462);
DISPLAY INVISIBLE (855 462);
FORCEPROP 2 LAST CDS_LIB mstr_discrete
J 0
(850 400);
PAINT ORANGE (850 400);
DISPLAY INVISIBLE (850 400);
FORCEPROP 0 LAST ROOM VDDQ_ABC_PWR_VR
J 0
(900 625);
DISPLAY 1.021277 (900 625);
PAINT ORANGE (900 625);
DISPLAY INVISIBLE (900 625);
FORCEPROP 1 LAST PATH I317
J 0
(900 575);
DISPLAY 0.978723 (900 575);
PAINT WHITE (900 575);
DISPLAY INVISIBLE (900 575);
FORCEPROP 2 LAST CDS_LOCATION R7G10
J 0
(895 525);
DISPLAY 0.617021 (895 525);
PAINT AQUA (895 525);
DISPLAY INVISIBLE (895 525);
FORCEPROP 2 LAST $SEC 1
J 0
(900 625);
PAINT MONO (900 625);
DISPLAY INVISIBLE (900 625);
FORCEPROP 2 LAST CDS_SEC 1
J 0
(900 625);
PAINT MONO (900 625);
DISPLAY INVISIBLE (900 625);
FORCEADD GND..1
(850 150);
FORCEPROP 3 LASTPIN (850 200) SIG_NAME GND\g
J 0
(860 210);
DISPLAY 0.659574 (860 210);
PAINT MONO (860 210);
DISPLAY INVISIBLE (860 210);
FORCEPROP 2 LAST ROOM VDDQ_ABC_PWR_VR
J 0
(275 225);
DISPLAY 1.361702 (275 225);
PAINT ORANGE (275 225);
DISPLAY INVISIBLE (275 225);
FORCEPROP 1 LAST PATH I318
J 0
(925 150);
DISPLAY 0.872340 (925 150);
PAINT AQUA (925 150);
DISPLAY INVISIBLE (925 150);
FORCEPROP 1 LAST BODY_TYPE PLUMBING
J 0
(805 107);
DISPLAY 0.340426 (805 107);
PAINT GREEN (805 107);
DISPLAY INVISIBLE (805 107);
FORCEPROP 1 LAST SIZE 1B
J 0
(925 100);
DISPLAY 1.170213 (925 100);
PAINT AQUA (925 100);
DISPLAY INVISIBLE (925 100);
FORCEPROP 2 LAST CDS_LIB mstr_symbols
J 0
(850 150);
PAINT ORANGE (850 150);
DISPLAY INVISIBLE (850 150);
FORCEPROP 1 LAST VOLTAGE 0
J 0
(850 150);
PAINT SKYBLUE (850 150);
DISPLAY INVISIBLE (850 150);
FORCEPROP 1 LAST HDL_POWER GND
J 0
(850 300);
DISPLAY 1.170213 (850 300);
PAINT GREEN (850 300);
DISPLAY INVISIBLE (850 300);
FORCEADD GND..1
(400 950);
FORCEPROP 3 LASTPIN (400 1000) SIG_NAME GND\g
J 0
(410 1010);
DISPLAY 0.659574 (410 1010);
PAINT MONO (410 1010);
DISPLAY INVISIBLE (410 1010);
FORCEPROP 2 LAST ROOM VDDQ_ABC_PWR_VR
J 0
(-175 1025);
DISPLAY 1.361702 (-175 1025);
PAINT ORANGE (-175 1025);
DISPLAY INVISIBLE (-175 1025);
FORCEPROP 1 LAST BODY_TYPE PLUMBING
J 0
(355 907);
DISPLAY 0.340426 (355 907);
PAINT GREEN (355 907);
DISPLAY INVISIBLE (355 907);
FORCEPROP 1 LAST SIZE 1B
J 0
(475 900);
DISPLAY 1.170213 (475 900);
PAINT AQUA (475 900);
DISPLAY INVISIBLE (475 900);
FORCEPROP 2 LAST CDS_LIB mstr_symbols
J 0
(400 950);
PAINT ORANGE (400 950);
DISPLAY INVISIBLE (400 950);
FORCEPROP 1 LAST VOLTAGE 0
J 0
(400 950);
PAINT SKYBLUE (400 950);
DISPLAY INVISIBLE (400 950);
FORCEPROP 1 LAST PATH I319
J 0
(475 950);
DISPLAY 0.872340 (475 950);
PAINT AQUA (475 950);
DISPLAY INVISIBLE (475 950);
FORCEPROP 1 LAST HDL_POWER GND
J 0
(400 1100);
DISPLAY 1.170213 (400 1100);
PAINT GREEN (400 1100);
DISPLAY INVISIBLE (400 1100);
FORCEADD CAP..1
R 2
(325 850);
FORCEPROP 1 LAST PART_NUMBER A36096-050
J 2
(275 800);
DISPLAY 0.617021 (275 800);
PAINT BLUE (275 800);
FORCEPROP 1 LAST TOLERANCE 10%
J 2
(100 900);
DISPLAY 0.617021 (100 900);
PAINT SKYBLUE (100 900);
FORCEPROP 1 LAST MATERIAL X7R
J 2
(150 850);
DISPLAY 0.617021 (150 850);
PAINT SKYBLUE (150 850);
FORCEPROP 1 LAST VOLTAGE 50V
J 2
(275 850);
DISPLAY 0.617021 (275 850);
PAINT SKYBLUE (275 850);
FORCEPROP 1 LAST PACK_TYPE 0402LF
J 2
(275 750);
DISPLAY 0.617021 (275 750);
PAINT SKYBLUE (275 750);
FORCEPROP 1 LAST LOCATION C7G3
J 2
(275 950);
DISPLAY 0.617021 (275 950);
PAINT AQUA (275 950);
FORCEPROP 1 LAST VALUE 220PF
J 2
(275 900);
DISPLAY 0.617021 (275 900);
PAINT SKYBLUE (275 900);
FORCEPROP 1 LASTPIN (325 750) $PN 2
J 2
(315 730);
DISPLAY 0.617021 (315 730);
PAINT ORANGE (315 730);
FORCEPROP 1 LASTPIN (325 950) $PN 1
J 2
(315 930);
DISPLAY 0.617021 (315 930);
PAINT ORANGE (315 930);
FORCEPROP 2 LAST CDS_LIB mstr_discrete
J 2
(325 850);
PAINT ORANGE (325 850);
DISPLAY INVISIBLE (325 850);
FORCEPROP 2 LAST CDS_LOCATION C7G3
J 2
(275 950);
DISPLAY 0.617021 (275 950);
PAINT AQUA (275 950);
DISPLAY INVISIBLE (275 950);
FORCEPROP 2 LAST ROOM VDDQ_ABC_PWR_VR
J 2
(275 1000);
DISPLAY 1.361702 (275 1000);
PAINT ORANGE (275 1000);
DISPLAY INVISIBLE (275 1000);
FORCEPROP 1 LAST PATH I320
J 2
(275 1000);
DISPLAY 0.978723 (275 1000);
PAINT WHITE (275 1000);
DISPLAY INVISIBLE (275 1000);
FORCEPROP 2 LAST SEC 1
J 2
(275 1075);
DISPLAY 0.680851 (275 1075);
PAINT MONO (275 1075);
DISPLAY INVISIBLE (275 1075);
FORCEPROP 2 LAST SEC_TYPE 0402LF
J 2
(275 1075);
DISPLAY 1.021277 (275 1075);
PAINT ORANGE (275 1075);
DISPLAY INVISIBLE (275 1075);
FORCEADD RES..2
(500 400);
FORCEPROP 1 LAST WATTAGE 1/16W
J 0
(540 375);
DISPLAY 0.617021 (540 375);
PAINT SKYBLUE (540 375);
FORCEPROP 1 LAST MATERIAL CHIP
J 0
(540 325);
DISPLAY 0.617021 (540 325);
PAINT SKYBLUE (540 325);
FORCEPROP 1 LAST PACK_TYPE 0402
J 0
(540 225);
DISPLAY 0.617021 (540 225);
PAINT SKYBLUE (540 225);
FORCEPROP 1 LAST TOLERANCE 1%
J 0
(545 425);
DISPLAY 0.617021 (545 425);
PAINT SKYBLUE (545 425);
FORCEPROP 1 LAST VALUE 4.02K
J 0
(545 475);
DISPLAY 0.617021 (545 475);
PAINT SKYBLUE (545 475);
FORCEPROP 1 LAST PART_NUMBER G21796-082
J 0
(540 275);
DISPLAY 0.617021 (540 275);
PAINT BLUE (540 275);
FORCEPROP 1 LAST LOCATION R7G8
J 0
(545 525);
DISPLAY 0.617021 (545 525);
PAINT AQUA (545 525);
FORCEPROP 1 LASTPIN (500 500) $PN 1
J 0
(505 462);
DISPLAY 0.787234 (505 462);
PAINT ORANGE (505 462);
DISPLAY INVISIBLE (505 462);
FORCEPROP 1 LASTPIN (500 300) $PN 2
J 0
(505 310);
DISPLAY 0.787234 (505 310);
PAINT ORANGE (505 310);
DISPLAY INVISIBLE (505 310);
FORCEPROP 2 LAST CDS_LIB mstr_discrete
J 0
(500 400);
PAINT ORANGE (500 400);
DISPLAY INVISIBLE (500 400);
FORCEPROP 0 LAST ROOM VDDQ_ABC_PWR_VR
J 0
(550 625);
DISPLAY 1.021277 (550 625);
PAINT ORANGE (550 625);
DISPLAY INVISIBLE (550 625);
FORCEPROP 1 LAST PATH I321
J 0
(550 575);
DISPLAY 0.978723 (550 575);
PAINT WHITE (550 575);
DISPLAY INVISIBLE (550 575);
FORCEPROP 2 LAST CDS_LOCATION R7G8
J 0
(545 525);
DISPLAY 0.617021 (545 525);
PAINT AQUA (545 525);
DISPLAY INVISIBLE (545 525);
FORCEPROP 2 LAST $SEC 1
J 0
(550 625);
PAINT MONO (550 625);
DISPLAY INVISIBLE (550 625);
FORCEPROP 2 LAST CDS_SEC 1
J 0
(550 625);
PAINT MONO (550 625);
DISPLAY INVISIBLE (550 625);
FORCEADD GND..1
(500 150);
FORCEPROP 3 LASTPIN (500 200) SIG_NAME GND\g
J 0
(510 210);
DISPLAY 0.659574 (510 210);
PAINT MONO (510 210);
DISPLAY INVISIBLE (510 210);
FORCEPROP 2 LAST ROOM VDDQ_ABC_PWR_VR
J 0
(-75 225);
DISPLAY 1.361702 (-75 225);
PAINT ORANGE (-75 225);
DISPLAY INVISIBLE (-75 225);
FORCEPROP 1 LAST BODY_TYPE PLUMBING
J 0
(455 107);
DISPLAY 0.340426 (455 107);
PAINT GREEN (455 107);
DISPLAY INVISIBLE (455 107);
FORCEPROP 2 LAST CDS_LIB mstr_symbols
J 0
(500 150);
PAINT ORANGE (500 150);
DISPLAY INVISIBLE (500 150);
FORCEPROP 1 LAST VOLTAGE 0
J 0
(500 150);
PAINT SKYBLUE (500 150);
DISPLAY INVISIBLE (500 150);
FORCEPROP 1 LAST HDL_POWER GND
J 0
(500 300);
DISPLAY 1.170213 (500 300);
PAINT GREEN (500 300);
DISPLAY INVISIBLE (500 300);
FORCEPROP 1 LAST PATH I322
J 0
(575 150);
DISPLAY 0.872340 (575 150);
PAINT AQUA (575 150);
DISPLAY INVISIBLE (575 150);
FORCEPROP 1 LAST SIZE 1B
J 0
(575 100);
DISPLAY 1.170213 (575 100);
PAINT AQUA (575 100);
DISPLAY INVISIBLE (575 100);
FORCEADD GND..1
(325 150);
FORCEPROP 3 LASTPIN (325 200) SIG_NAME GND\g
J 0
(335 210);
DISPLAY 0.659574 (335 210);
PAINT MONO (335 210);
DISPLAY INVISIBLE (335 210);
FORCEPROP 2 LAST ROOM VDDQ_ABC_PWR_VR
J 0
(-250 225);
DISPLAY 1.361702 (-250 225);
PAINT ORANGE (-250 225);
DISPLAY INVISIBLE (-250 225);
FORCEPROP 1 LAST VOLTAGE 0
J 0
(325 150);
PAINT SKYBLUE (325 150);
DISPLAY INVISIBLE (325 150);
FORCEPROP 2 LAST CDS_LIB mstr_symbols
J 0
(325 150);
PAINT ORANGE (325 150);
DISPLAY INVISIBLE (325 150);
FORCEPROP 1 LAST BODY_TYPE PLUMBING
J 0
(280 107);
DISPLAY 0.340426 (280 107);
PAINT GREEN (280 107);
DISPLAY INVISIBLE (280 107);
FORCEPROP 1 LAST SIZE 1B
J 0
(400 100);
DISPLAY 1.170213 (400 100);
PAINT AQUA (400 100);
DISPLAY INVISIBLE (400 100);
FORCEPROP 1 LAST PATH I323
J 0
(400 150);
DISPLAY 0.872340 (400 150);
PAINT AQUA (400 150);
DISPLAY INVISIBLE (400 150);
FORCEPROP 1 LAST HDL_POWER GND
J 0
(325 300);
DISPLAY 1.170213 (325 300);
PAINT GREEN (325 300);
DISPLAY INVISIBLE (325 300);
FORCEADD CAP_A..1
(3000 500);
FORCEPROP 1 LASTPIN (3000 400) $PN 2
J 0
(3010 380);
DISPLAY 0.617021 (3010 380);
PAINT ORANGE (3010 380);
FORCEPROP 1 LASTPIN (3000 600) $PN 1
J 0
(3010 580);
DISPLAY 0.617021 (3010 580);
PAINT ORANGE (3010 580);
FORCEPROP 1 LAST MATERIAL X6S
J 0
(3050 400);
DISPLAY 0.617021 (3050 400);
PAINT SKYBLUE (3050 400);
FORCEPROP 1 LAST VOLTAGE 6.3V
J 0
(3050 500);
DISPLAY 0.617021 (3050 500);
PAINT SKYBLUE (3050 500);
FORCEPROP 1 LAST PACK_TYPE 0402V
J 0
(3050 300);
DISPLAY 0.617021 (3050 300);
PAINT SKYBLUE (3050 300);
FORCEPROP 1 LAST TOLERANCE 10%
J 0
(3050 450);
DISPLAY 0.617021 (3050 450);
PAINT SKYBLUE (3050 450);
FORCEPROP 1 LAST VALUE 1.0UF
J 0
(3050 550);
DISPLAY 0.617021 (3050 550);
PAINT SKYBLUE (3050 550);
FORCEPROP 1 LAST PART_NUMBER D97712-004
J 0
(3050 350);
DISPLAY 0.617021 (3050 350);
PAINT BLUE (3050 350);
FORCEPROP 1 LAST LOCATION C7F16
J 0
(3050 600);
DISPLAY 0.617021 (3050 600);
PAINT AQUA (3050 600);
FORCEPROP 2 LAST CDS_LIB dev_discrete
J 0
(3000 500);
PAINT ORANGE (3000 500);
DISPLAY INVISIBLE (3000 500);
FORCEPROP 2 LAST CDS_LOCATION C7F16
J 0
(3050 600);
DISPLAY 0.617021 (3050 600);
PAINT AQUA (3050 600);
DISPLAY INVISIBLE (3050 600);
FORCEPROP 2 LAST CDS_SEC 1
J 0
(3050 650);
PAINT ORANGE (3050 650);
DISPLAY INVISIBLE (3050 650);
FORCEPROP 2 LAST SEC_TYPE 0402V
J 0
(3050 700);
DISPLAY 1.021277 (3050 700);
PAINT ORANGE (3050 700);
DISPLAY INVISIBLE (3050 700);
FORCEPROP 2 LAST SEC 1
J 0
(3050 700);
DISPLAY 0.680851 (3050 700);
PAINT MONO (3050 700);
DISPLAY INVISIBLE (3050 700);
FORCEPROP 1 LAST PATH I325
J 0
(3050 650);
DISPLAY 0.978723 (3050 650);
PAINT WHITE (3050 650);
DISPLAY INVISIBLE (3050 650);
FORCEPROP 2 LAST ROOM VDDQ_ABC_PWR_VR
J 0
(3050 650);
DISPLAY 1.361702 (3050 650);
PAINT ORANGE (3050 650);
DISPLAY INVISIBLE (3050 650);
FORCEADD GND..1
(3000 225);
FORCEPROP 3 LASTPIN (3000 275) SIG_NAME GND\g
J 0
(3010 285);
DISPLAY 0.659574 (3010 285);
PAINT MONO (3010 285);
DISPLAY INVISIBLE (3010 285);
FORCEPROP 2 LAST ROOM VDDQ_ABC_PWR_VR
J 0
(2425 300);
DISPLAY 1.361702 (2425 300);
PAINT ORANGE (2425 300);
DISPLAY INVISIBLE (2425 300);
FORCEPROP 1 LAST BODY_TYPE PLUMBING
J 0
(2955 182);
DISPLAY 0.340426 (2955 182);
PAINT GREEN (2955 182);
DISPLAY INVISIBLE (2955 182);
FORCEPROP 1 LAST VOLTAGE 0
J 0
(3000 225);
PAINT SKYBLUE (3000 225);
DISPLAY INVISIBLE (3000 225);
FORCEPROP 2 LAST CDS_LIB mstr_symbols
J 0
(3000 225);
PAINT ORANGE (3000 225);
DISPLAY INVISIBLE (3000 225);
FORCEPROP 1 LAST HDL_POWER GND
J 0
(3000 375);
DISPLAY 1.170213 (3000 375);
PAINT GREEN (3000 375);
DISPLAY INVISIBLE (3000 375);
FORCEPROP 1 LAST SIZE 1B
J 0
(3075 175);
DISPLAY 1.170213 (3075 175);
PAINT AQUA (3075 175);
DISPLAY INVISIBLE (3075 175);
FORCEPROP 1 LAST PATH I326
J 0
(3075 225);
DISPLAY 0.872340 (3075 225);
PAINT AQUA (3075 225);
DISPLAY INVISIBLE (3075 225);
FORCEADD CAP_A..1
(2600 500);
FORCEPROP 1 LASTPIN (2600 400) $PN 2
J 0
(2610 380);
DISPLAY 0.617021 (2610 380);
PAINT ORANGE (2610 380);
FORCEPROP 1 LAST MATERIAL X7R
J 0
(2650 400);
DISPLAY 0.617021 (2650 400);
PAINT SKYBLUE (2650 400);
FORCEPROP 1 LAST PACK_TYPE 0402V
J 0
(2650 300);
DISPLAY 0.617021 (2650 300);
PAINT SKYBLUE (2650 300);
FORCEPROP 1 LAST TOLERANCE 10%
J 0
(2650 450);
DISPLAY 0.617021 (2650 450);
PAINT SKYBLUE (2650 450);
FORCEPROP 1 LAST PART_NUMBER A36096-030
J 0
(2650 350);
DISPLAY 0.617021 (2650 350);
PAINT BLUE (2650 350);
FORCEPROP 1 LAST VOLTAGE 16V
J 0
(2650 500);
DISPLAY 0.617021 (2650 500);
PAINT SKYBLUE (2650 500);
FORCEPROP 1 LAST LOCATION C7F15
J 0
(2650 600);
DISPLAY 0.617021 (2650 600);
PAINT AQUA (2650 600);
FORCEPROP 1 LAST VALUE 0.1UF
J 0
(2650 550);
DISPLAY 0.617021 (2650 550);
PAINT SKYBLUE (2650 550);
FORCEPROP 1 LASTPIN (2600 600) $PN 1
J 0
(2610 580);
DISPLAY 0.617021 (2610 580);
PAINT ORANGE (2610 580);
FORCEPROP 2 LAST CDS_LIB dev_discrete
J 0
(2600 500);
PAINT ORANGE (2600 500);
DISPLAY INVISIBLE (2600 500);
FORCEPROP 1 LAST PATH I327
J 0
(2650 650);
DISPLAY 0.978723 (2650 650);
PAINT WHITE (2650 650);
DISPLAY INVISIBLE (2650 650);
FORCEPROP 2 LAST ROOM VDDQ_ABC_PWR_VR
J 0
(2650 650);
DISPLAY 1.361702 (2650 650);
PAINT ORANGE (2650 650);
DISPLAY INVISIBLE (2650 650);
FORCEPROP 2 LAST CDS_LOCATION C7F15
J 0
(2650 600);
DISPLAY 0.617021 (2650 600);
PAINT AQUA (2650 600);
DISPLAY INVISIBLE (2650 600);
FORCEPROP 2 LAST CDS_SEC 1
J 0
(2650 650);
PAINT ORANGE (2650 650);
DISPLAY INVISIBLE (2650 650);
FORCEPROP 2 LAST SEC_TYPE 0402V
J 0
(2650 725);
DISPLAY 1.021277 (2650 725);
PAINT ORANGE (2650 725);
DISPLAY INVISIBLE (2650 725);
FORCEPROP 2 LAST SEC 1
J 0
(2650 725);
DISPLAY 0.680851 (2650 725);
PAINT MONO (2650 725);
DISPLAY INVISIBLE (2650 725);
FORCEADD GND..1
(2600 300);
FORCEPROP 3 LASTPIN (2600 350) SIG_NAME GND\g
J 0
(2610 360);
DISPLAY 0.659574 (2610 360);
PAINT MONO (2610 360);
DISPLAY INVISIBLE (2610 360);
FORCEPROP 2 LAST ROOM VDDQ_ABC_PWR_VR
J 0
(2025 375);
DISPLAY 1.361702 (2025 375);
PAINT ORANGE (2025 375);
DISPLAY INVISIBLE (2025 375);
FORCEPROP 1 LAST BODY_TYPE PLUMBING
J 0
(2555 257);
DISPLAY 0.340426 (2555 257);
PAINT GREEN (2555 257);
DISPLAY INVISIBLE (2555 257);
FORCEPROP 1 LAST SIZE 1B
J 0
(2675 250);
DISPLAY 1.170213 (2675 250);
PAINT AQUA (2675 250);
DISPLAY INVISIBLE (2675 250);
FORCEPROP 1 LAST VOLTAGE 0
J 0
(2600 300);
PAINT SKYBLUE (2600 300);
DISPLAY INVISIBLE (2600 300);
FORCEPROP 2 LAST CDS_LIB mstr_symbols
J 0
(2600 300);
PAINT ORANGE (2600 300);
DISPLAY INVISIBLE (2600 300);
FORCEPROP 1 LAST PATH I328
J 0
(2675 300);
DISPLAY 0.872340 (2675 300);
PAINT AQUA (2675 300);
DISPLAY INVISIBLE (2675 300);
FORCEPROP 1 LAST HDL_POWER GND
J 0
(2600 450);
DISPLAY 1.170213 (2600 450);
PAINT GREEN (2600 450);
DISPLAY INVISIBLE (2600 450);
FORCEADD PVCCIO_CPU0..1
(-100 3900);
FORCEPROP 3 LASTPIN (-100 3850) SIG_NAME PVCCIO_CPU0\g
J 0
(-90 3860);
DISPLAY 0.659574 (-90 3860);
PAINT MONO (-90 3860);
DISPLAY INVISIBLE (-90 3860);
FORCEPROP 1 LAST HDL_POWER PVCCIO_CPU0
J 1
(-100 3950);
DISPLAY 0.872340 (-100 3950);
PAINT GREEN (-100 3950);
DISPLAY INVISIBLE (-100 3950);
FORCEPROP 1 LAST PATH I329
J 0
(-50 3925);
DISPLAY 0.872340 (-50 3925);
PAINT AQUA (-50 3925);
DISPLAY INVISIBLE (-50 3925);
FORCEPROP 1 LAST BODY_TYPE PLUMBING
J 0
(-145 3857);
DISPLAY 0.340426 (-145 3857);
PAINT GREEN (-145 3857);
DISPLAY INVISIBLE (-145 3857);
FORCEPROP 2 LAST CDS_LIB mstr_symbols
J 0
(-100 3900);
PAINT ORANGE (-100 3900);
DISPLAY INVISIBLE (-100 3900);
FORCEPROP 1 LAST VOLTAGE 1.1V
J 0
(-145 3857);
DISPLAY 0.340426 (-145 3857);
PAINT SKYBLUE (-145 3857);
DISPLAY INVISIBLE (-145 3857);
FORCEADD RES..2
(-100 3625);
FORCEPROP 1 LASTPIN (-100 3525) $PN 2
J 0
(-95 3535);
DISPLAY 0.617021 (-95 3535);
PAINT ORANGE (-95 3535);
FORCEPROP 1 LASTPIN (-100 3725) $PN 1
J 0
(-95 3687);
DISPLAY 0.617021 (-95 3687);
PAINT ORANGE (-95 3687);
FORCEPROP 1 LAST WATTAGE 1/16W
J 0
(-60 3600);
DISPLAY 0.617021 (-60 3600);
PAINT SKYBLUE (-60 3600);
FORCEPROP 1 LAST PACK_TYPE 0402
J 0
(-60 3450);
DISPLAY 0.617021 (-60 3450);
PAINT SKYBLUE (-60 3450);
FORCEPROP 1 LAST TOLERANCE 1%
J 0
(-55 3650);
DISPLAY 0.617021 (-55 3650);
PAINT SKYBLUE (-55 3650);
FORCEPROP 1 LAST VALUE 49.9
J 0
(-55 3700);
DISPLAY 0.617021 (-55 3700);
PAINT SKYBLUE (-55 3700);
FORCEPROP 1 LAST PART_NUMBER G21796-047
J 0
(-60 3500);
DISPLAY 0.617021 (-60 3500);
PAINT BLUE (-60 3500);
FORCEPROP 1 LAST LOCATION R3T11
J 0
(-55 3750);
DISPLAY 0.617021 (-55 3750);
PAINT AQUA (-55 3750);
FORCEPROP 1 LAST MATERIAL EMPTY
J 0
(-60 3550);
DISPLAY 0.617021 (-60 3550);
PAINT RED (-60 3550);
FORCEPROP 2 LAST CDS_LIB mstr_discrete
J 0
(-100 3625);
PAINT ORANGE (-100 3625);
DISPLAY INVISIBLE (-100 3625);
FORCEPROP 2 LAST CDS_LOCATION R3T11
J 0
(-55 3750);
DISPLAY 0.617021 (-55 3750);
PAINT AQUA (-55 3750);
DISPLAY INVISIBLE (-55 3750);
FORCEPROP 2 LAST ROOM VDDQ_ABC_PWR_VR
J 0
(-50 3800);
DISPLAY 1.361702 (-50 3800);
PAINT ORANGE (-50 3800);
DISPLAY INVISIBLE (-50 3800);
FORCEPROP 1 LAST PATH I330
J 0
(-50 3800);
DISPLAY 0.978723 (-50 3800);
PAINT WHITE (-50 3800);
DISPLAY INVISIBLE (-50 3800);
FORCEPROP 2 LAST SEC 1
J 0
(-50 3875);
PAINT MONO (-50 3875);
DISPLAY INVISIBLE (-50 3875);
FORCEPROP 2 LAST SEC_TYPE 0402
J 0
(-50 3875);
DISPLAY 1.021277 (-50 3875);
PAINT ORANGE (-50 3875);
DISPLAY INVISIBLE (-50 3875);
FORCEADD RES..1
(125 3100);
FORCEPROP 1 LAST VALUE 150.0
J 2
(125 3175);
DISPLAY 0.617021 (125 3175);
PAINT SKYBLUE (125 3175);
FORCEPROP 1 LASTPIN (25 3100) $PN 1
J 0
(37 3112);
DISPLAY 0.617021 (37 3112);
PAINT ORANGE (37 3112);
FORCEPROP 1 LAST WATTAGE 1/16W
J 2
(175 3125);
DISPLAY 0.617021 (175 3125);
PAINT SKYBLUE (175 3125);
FORCEPROP 1 LAST LOCATION R7G24
J 0
(25 3275);
DISPLAY 0.617021 (25 3275);
PAINT AQUA (25 3275);
FORCEPROP 1 LAST TOLERANCE 1%
J 0
(175 3175);
DISPLAY 0.617021 (175 3175);
PAINT SKYBLUE (175 3175);
FORCEPROP 1 LASTPIN (225 3100) $PN 2
J 0
(187 3112);
DISPLAY 0.617021 (187 3112);
PAINT ORANGE (187 3112);
FORCEPROP 1 LAST MATERIAL CHIP
J 0
(225 3125);
DISPLAY 0.617021 (225 3125);
PAINT SKYBLUE (225 3125);
FORCEPROP 1 LAST PART_NUMBER G21796-009
J 0
(25 3225);
DISPLAY 0.617021 (25 3225);
PAINT BLUE (25 3225);
FORCEPROP 1 LAST PACK_TYPE 0402
J 0
(300 3175);
DISPLAY 0.617021 (300 3175);
PAINT SKYBLUE (300 3175);
FORCEPROP 2 LAST CDS_LIB mstr_discrete
J 0
(125 3100);
PAINT ORANGE (125 3100);
DISPLAY INVISIBLE (125 3100);
FORCEPROP 1 LAST PATH I331
J 0
(75 3250);
DISPLAY 0.978723 (75 3250);
PAINT WHITE (75 3250);
DISPLAY INVISIBLE (75 3250);
FORCEPROP 2 LAST SEC_TYPE 0402
J 0
(75 3325);
DISPLAY 1.021277 (75 3325);
PAINT ORANGE (75 3325);
DISPLAY INVISIBLE (75 3325);
FORCEPROP 2 LAST SEC 1
J 0
(75 3325);
DISPLAY 0.680851 (75 3325);
PAINT MONO (75 3325);
DISPLAY INVISIBLE (75 3325);
FORCEPROP 2 LAST ROOM VDDQ_ABC_PWR_VR
J 0
(25 3325);
DISPLAY 1.361702 (25 3325);
PAINT ORANGE (25 3325);
DISPLAY INVISIBLE (25 3325);
FORCEADD RES..1
(-300 2925);
FORCEPROP 1 LAST TOLERANCE 5%
J 0
(-350 2825);
DISPLAY 0.617021 (-350 2825);
PAINT SKYBLUE (-350 2825);
FORCEPROP 1 LAST VALUE 0.0
J 2
(-400 2825);
DISPLAY 0.617021 (-400 2825);
PAINT SKYBLUE (-400 2825);
FORCEPROP 1 LAST WATTAGE 1/16W
J 2
(-325 2775);
DISPLAY 0.617021 (-325 2775);
PAINT SKYBLUE (-325 2775);
FORCEPROP 1 LAST MATERIAL CHIP
J 0
(-300 2775);
DISPLAY 0.617021 (-300 2775);
PAINT SKYBLUE (-300 2775);
FORCEPROP 1 LAST LOCATION R3U3
J 0
(-350 2975);
DISPLAY 0.617021 (-350 2975);
PAINT AQUA (-350 2975);
FORCEPROP 1 LAST PART_NUMBER G21497-005
J 0
(-450 2875);
DISPLAY 0.617021 (-450 2875);
PAINT BLUE (-450 2875);
FORCEPROP 1 LAST PACK_TYPE 0402
J 0
(-225 2825);
DISPLAY 0.617021 (-225 2825);
PAINT SKYBLUE (-225 2825);
FORCEPROP 2 LAST CDS_LIB mstr_discrete
J 0
(-300 2925);
PAINT ORANGE (-300 2925);
DISPLAY INVISIBLE (-300 2925);
FORCEPROP 1 LASTPIN (-400 2925) $PN 1
J 0
(-388 2937);
DISPLAY 0.787234 (-388 2937);
PAINT ORANGE (-388 2937);
DISPLAY INVISIBLE (-388 2937);
FORCEPROP 2 LAST CDS_LOCATION R3U3
J 0
(-350 2975);
DISPLAY 0.617021 (-350 2975);
PAINT AQUA (-350 2975);
DISPLAY INVISIBLE (-350 2975);
FORCEPROP 1 LASTPIN (-200 2925) $PN 2
J 0
(-238 2937);
DISPLAY 0.787234 (-238 2937);
PAINT ORANGE (-238 2937);
DISPLAY INVISIBLE (-238 2937);
FORCEPROP 2 LAST ROOM PVCCIN_CPU0_VR
J 0
(-350 3025);
DISPLAY 1.361702 (-350 3025);
PAINT ORANGE (-350 3025);
DISPLAY INVISIBLE (-350 3025);
FORCEPROP 1 LAST PATH I332
J 0
(-350 3075);
DISPLAY 0.978723 (-350 3075);
PAINT WHITE (-350 3075);
DISPLAY INVISIBLE (-350 3075);
FORCEPROP 2 LAST $SEC 1
J 0
(-350 3125);
PAINT MONO (-350 3125);
DISPLAY INVISIBLE (-350 3125);
FORCEPROP 2 LAST CDS_SEC 1
J 0
(-350 3125);
PAINT MONO (-350 3125);
DISPLAY INVISIBLE (-350 3125);
FORCEADD VCC_CORE..1
(-950 4000);
FORCEPROP 3 LASTPIN (-950 3950) SIG_NAME VR_FET_SW_P12V_STBY_PVDDQ_ABC\g
J 0
(-940 3960);
DISPLAY 0.659574 (-940 3960);
PAINT MONO (-940 3960);
DISPLAY INVISIBLE (-940 3960);
FORCEPROP 1 LAST HDL_POWER VR_FET_SW_P12V_STBY_PVDDQ_ABC
J 1
(-1225 4050);
DISPLAY 0.617021 (-1225 4050);
PAINT GREEN (-1225 4050);
FORCEPROP 1 LAST PATH I335
J 0
(-900 4025);
DISPLAY 0.872340 (-900 4025);
PAINT AQUA (-900 4025);
DISPLAY INVISIBLE (-900 4025);
FORCEPROP 2 LAST CDS_LIB mstr_symbols
J 0
(-950 4000);
PAINT ORANGE (-950 4000);
DISPLAY INVISIBLE (-950 4000);
FORCEADD RES..2
(-950 3775);
FORCEPROP 1 LASTPIN (-950 3675) $PN 2
J 0
(-945 3685);
DISPLAY 0.617021 (-945 3685);
PAINT ORANGE (-945 3685);
FORCEPROP 1 LAST TOLERANCE 1%
J 0
(-905 3800);
DISPLAY 0.617021 (-905 3800);
PAINT SKYBLUE (-905 3800);
FORCEPROP 1 LAST PACK_TYPE 0402
J 0
(-910 3600);
DISPLAY 0.617021 (-910 3600);
PAINT SKYBLUE (-910 3600);
FORCEPROP 1 LAST MATERIAL CHIP
J 0
(-910 3700);
DISPLAY 0.617021 (-910 3700);
PAINT SKYBLUE (-910 3700);
FORCEPROP 1 LAST WATTAGE 1/16W
J 0
(-910 3750);
DISPLAY 0.617021 (-910 3750);
PAINT SKYBLUE (-910 3750);
FORCEPROP 1 LAST VALUE 100.0K
J 0
(-905 3850);
DISPLAY 0.617021 (-905 3850);
PAINT SKYBLUE (-905 3850);
FORCEPROP 1 LAST PART_NUMBER G21796-160
J 0
(-910 3650);
DISPLAY 0.617021 (-910 3650);
PAINT BLUE (-910 3650);
FORCEPROP 1 LASTPIN (-950 3875) $PN 1
J 0
(-945 3837);
DISPLAY 0.617021 (-945 3837);
PAINT ORANGE (-945 3837);
FORCEPROP 1 LAST LOCATION R7F34
J 0
(-905 3900);
DISPLAY 0.617021 (-905 3900);
PAINT AQUA (-905 3900);
FORCEPROP 2 LAST CDS_LIB mstr_discrete
J 0
(-950 3775);
PAINT ORANGE (-950 3775);
DISPLAY INVISIBLE (-950 3775);
FORCEPROP 2 LAST CDS_LOCATION R7F34
J 0
(-905 3900);
DISPLAY 0.617021 (-905 3900);
PAINT AQUA (-905 3900);
DISPLAY INVISIBLE (-905 3900);
FORCEPROP 2 LAST ROOM VDDQ_ABC_PWR_VR
J 0
(-900 3950);
DISPLAY 1.361702 (-900 3950);
PAINT ORANGE (-900 3950);
DISPLAY INVISIBLE (-900 3950);
FORCEPROP 1 LAST PATH I336
J 0
(-900 3950);
DISPLAY 0.978723 (-900 3950);
PAINT WHITE (-900 3950);
DISPLAY INVISIBLE (-900 3950);
FORCEPROP 2 LAST SEC 1
J 0
(-900 4000);
DISPLAY 0.680851 (-900 4000);
PAINT MONO (-900 4000);
DISPLAY INVISIBLE (-900 4000);
FORCEPROP 2 LAST SEC_TYPE 0402
J 0
(-900 4000);
DISPLAY 1.021277 (-900 4000);
PAINT ORANGE (-900 4000);
DISPLAY INVISIBLE (-900 4000);
FORCEADD RES..2
(-950 3400);
FORCEPROP 1 LAST PACK_TYPE 0402
J 0
(-910 3225);
DISPLAY 0.617021 (-910 3225);
PAINT SKYBLUE (-910 3225);
FORCEPROP 1 LASTPIN (-950 3300) $PN 2
J 0
(-945 3310);
DISPLAY 0.617021 (-945 3310);
PAINT ORANGE (-945 3310);
FORCEPROP 1 LAST MATERIAL CHIP
J 0
(-910 3325);
DISPLAY 0.617021 (-910 3325);
PAINT SKYBLUE (-910 3325);
FORCEPROP 1 LASTPIN (-950 3500) $PN 1
J 0
(-945 3462);
DISPLAY 0.617021 (-945 3462);
PAINT ORANGE (-945 3462);
FORCEPROP 1 LAST LOCATION R7G3
J 0
(-905 3525);
DISPLAY 0.617021 (-905 3525);
PAINT AQUA (-905 3525);
FORCEPROP 1 LAST VALUE 1.5K
J 0
(-905 3475);
DISPLAY 0.617021 (-905 3475);
PAINT SKYBLUE (-905 3475);
FORCEPROP 1 LAST TOLERANCE 1%
J 0
(-905 3425);
DISPLAY 0.617021 (-905 3425);
PAINT SKYBLUE (-905 3425);
FORCEPROP 1 LAST WATTAGE 1/16W
J 0
(-910 3375);
DISPLAY 0.617021 (-910 3375);
PAINT SKYBLUE (-910 3375);
FORCEPROP 1 LAST PART_NUMBER G21796-003
J 0
(-910 3275);
DISPLAY 0.617021 (-910 3275);
PAINT BLUE (-910 3275);
FORCEPROP 2 LAST CDS_LIB mstr_discrete
J 0
(-950 3400);
PAINT ORANGE (-950 3400);
DISPLAY INVISIBLE (-950 3400);
FORCEPROP 2 LAST CDS_LOCATION R7G3
J 0
(-905 3525);
DISPLAY 0.617021 (-905 3525);
PAINT AQUA (-905 3525);
DISPLAY INVISIBLE (-905 3525);
FORCEPROP 2 LAST ROOM VDDQ_ABC_PWR_VR
J 0
(-900 3575);
DISPLAY 1.361702 (-900 3575);
PAINT ORANGE (-900 3575);
DISPLAY INVISIBLE (-900 3575);
FORCEPROP 1 LAST PATH I337
J 0
(-900 3575);
DISPLAY 0.978723 (-900 3575);
PAINT WHITE (-900 3575);
DISPLAY INVISIBLE (-900 3575);
FORCEPROP 2 LAST SEC_TYPE 0402
J 0
(-900 3625);
DISPLAY 1.021277 (-900 3625);
PAINT ORANGE (-900 3625);
DISPLAY INVISIBLE (-900 3625);
FORCEPROP 2 LAST SEC 1
J 0
(-900 3625);
DISPLAY 0.680851 (-900 3625);
PAINT MONO (-900 3625);
DISPLAY INVISIBLE (-900 3625);
FORCEADD GND..1
(-950 3150);
FORCEPROP 3 LASTPIN (-950 3200) SIG_NAME GND\g
J 0
(-940 3210);
DISPLAY 0.659574 (-940 3210);
PAINT MONO (-940 3210);
DISPLAY INVISIBLE (-940 3210);
FORCEPROP 2 LAST ROOM VDDQ_ABC_PWR_VR
J 0
(-1525 3225);
DISPLAY 1.361702 (-1525 3225);
PAINT ORANGE (-1525 3225);
DISPLAY INVISIBLE (-1525 3225);
FORCEPROP 1 LAST VOLTAGE 0
J 0
(-950 3150);
PAINT SKYBLUE (-950 3150);
DISPLAY INVISIBLE (-950 3150);
FORCEPROP 2 LAST CDS_LIB mstr_symbols
J 0
(-950 3150);
PAINT ORANGE (-950 3150);
DISPLAY INVISIBLE (-950 3150);
FORCEPROP 1 LAST BODY_TYPE PLUMBING
J 0
(-995 3107);
DISPLAY 0.340426 (-995 3107);
PAINT GREEN (-995 3107);
DISPLAY INVISIBLE (-995 3107);
FORCEPROP 1 LAST SIZE 1B
J 0
(-875 3100);
DISPLAY 1.170213 (-875 3100);
PAINT AQUA (-875 3100);
DISPLAY INVISIBLE (-875 3100);
FORCEPROP 1 LAST PATH I338
J 0
(-875 3150);
DISPLAY 0.872340 (-875 3150);
PAINT AQUA (-875 3150);
DISPLAY INVISIBLE (-875 3150);
FORCEPROP 1 LAST HDL_POWER GND
J 0
(-950 3300);
DISPLAY 1.170213 (-950 3300);
PAINT GREEN (-950 3300);
DISPLAY INVISIBLE (-950 3300);
FORCEADD CAP..1
R 2
(-1175 3400);
FORCEPROP 1 LASTPIN (-1175 3300) $PN 2
J 2
(-1185 3280);
DISPLAY 0.617021 (-1185 3280);
PAINT ORANGE (-1185 3280);
FORCEPROP 1 LASTPIN (-1175 3500) $PN 1
J 2
(-1185 3480);
DISPLAY 0.617021 (-1185 3480);
PAINT ORANGE (-1185 3480);
FORCEPROP 1 LAST PACK_TYPE 0402LF
J 2
(-1225 3200);
DISPLAY 0.617021 (-1225 3200);
PAINT SKYBLUE (-1225 3200);
FORCEPROP 1 LAST PART_NUMBER A36096-046
J 2
(-1225 3250);
DISPLAY 0.617021 (-1225 3250);
PAINT BLUE (-1225 3250);
FORCEPROP 1 LAST MATERIAL X7R
J 2
(-1225 3300);
DISPLAY 0.617021 (-1225 3300);
PAINT SKYBLUE (-1225 3300);
FORCEPROP 1 LAST TOLERANCE 10%
J 2
(-1225 3350);
DISPLAY 0.617021 (-1225 3350);
PAINT SKYBLUE (-1225 3350);
FORCEPROP 1 LAST VOLTAGE 50V
J 2
(-1225 3400);
DISPLAY 0.617021 (-1225 3400);
PAINT SKYBLUE (-1225 3400);
FORCEPROP 1 LAST VALUE 1000PF
J 2
(-1225 3450);
DISPLAY 0.617021 (-1225 3450);
PAINT SKYBLUE (-1225 3450);
FORCEPROP 1 LAST LOCATION C7G1
J 2
(-1225 3500);
DISPLAY 0.617021 (-1225 3500);
PAINT AQUA (-1225 3500);
FORCEPROP 2 LAST CDS_LOCATION C7G1
J 2
(-1225 3500);
DISPLAY 0.617021 (-1225 3500);
PAINT AQUA (-1225 3500);
DISPLAY INVISIBLE (-1225 3500);
FORCEPROP 2 LAST CDS_LIB mstr_discrete
J 2
(-1175 3400);
PAINT ORANGE (-1175 3400);
DISPLAY INVISIBLE (-1175 3400);
FORCEPROP 2 LAST ROOM VDDQ_ABC_PWR_VR
J 0
(-1225 3550);
DISPLAY 1.361702 (-1225 3550);
PAINT ORANGE (-1225 3550);
DISPLAY INVISIBLE (-1225 3550);
FORCEPROP 1 LAST PATH I339
J 2
(-1225 3550);
DISPLAY 0.978723 (-1225 3550);
PAINT WHITE (-1225 3550);
DISPLAY INVISIBLE (-1225 3550);
FORCEPROP 2 LAST SEC 1
J 0
(-1225 3625);
DISPLAY 0.680851 (-1225 3625);
PAINT MONO (-1225 3625);
DISPLAY INVISIBLE (-1225 3625);
FORCEPROP 2 LAST SEC_TYPE 0402LF
J 0
(-1225 3625);
DISPLAY 1.021277 (-1225 3625);
PAINT ORANGE (-1225 3625);
DISPLAY INVISIBLE (-1225 3625);
FORCEADD GND..1
(-1175 3150);
FORCEPROP 3 LASTPIN (-1175 3200) SIG_NAME GND\g
J 0
(-1165 3210);
DISPLAY 0.659574 (-1165 3210);
PAINT MONO (-1165 3210);
DISPLAY INVISIBLE (-1165 3210);
FORCEPROP 2 LAST ROOM VDDQ_ABC_PWR_VR
J 0
(-1750 3225);
DISPLAY 1.361702 (-1750 3225);
PAINT ORANGE (-1750 3225);
DISPLAY INVISIBLE (-1750 3225);
FORCEPROP 1 LAST VOLTAGE 0
J 0
(-1175 3150);
PAINT SKYBLUE (-1175 3150);
DISPLAY INVISIBLE (-1175 3150);
FORCEPROP 2 LAST CDS_LIB mstr_symbols
J 0
(-1175 3150);
PAINT ORANGE (-1175 3150);
DISPLAY INVISIBLE (-1175 3150);
FORCEPROP 1 LAST BODY_TYPE PLUMBING
J 0
(-1220 3107);
DISPLAY 0.340426 (-1220 3107);
PAINT GREEN (-1220 3107);
DISPLAY INVISIBLE (-1220 3107);
FORCEPROP 1 LAST SIZE 1B
J 0
(-1100 3100);
DISPLAY 1.170213 (-1100 3100);
PAINT AQUA (-1100 3100);
DISPLAY INVISIBLE (-1100 3100);
FORCEPROP 1 LAST PATH I340
J 0
(-1100 3150);
DISPLAY 0.872340 (-1100 3150);
PAINT AQUA (-1100 3150);
DISPLAY INVISIBLE (-1100 3150);
FORCEPROP 1 LAST HDL_POWER GND
J 0
(-1175 3300);
DISPLAY 1.170213 (-1175 3300);
PAINT GREEN (-1175 3300);
DISPLAY INVISIBLE (-1175 3300);
FORCEADD RES..1
(-1225 2775);
FORCEPROP 1 LAST VALUE 0.0
J 2
(-1325 2675);
DISPLAY 0.617021 (-1325 2675);
PAINT SKYBLUE (-1325 2675);
FORCEPROP 1 LAST WATTAGE 1/16W
J 2
(-1250 2625);
DISPLAY 0.617021 (-1250 2625);
PAINT SKYBLUE (-1250 2625);
FORCEPROP 1 LAST PART_NUMBER G21497-005
J 0
(-1375 2725);
DISPLAY 0.617021 (-1375 2725);
PAINT BLUE (-1375 2725);
FORCEPROP 1 LAST MATERIAL CHIP
J 0
(-1225 2625);
DISPLAY 0.617021 (-1225 2625);
PAINT SKYBLUE (-1225 2625);
FORCEPROP 1 LAST PACK_TYPE 0402
J 0
(-1150 2675);
DISPLAY 0.617021 (-1150 2675);
PAINT SKYBLUE (-1150 2675);
FORCEPROP 1 LAST TOLERANCE 5%
J 0
(-1275 2675);
DISPLAY 0.617021 (-1275 2675);
PAINT SKYBLUE (-1275 2675);
FORCEPROP 1 LAST LOCATION R3U10
J 0
(-1275 2825);
DISPLAY 0.617021 (-1275 2825);
PAINT AQUA (-1275 2825);
FORCEPROP 1 LASTPIN (-1325 2775) $PN 1
J 0
(-1313 2787);
DISPLAY 0.787234 (-1313 2787);
PAINT ORANGE (-1313 2787);
DISPLAY INVISIBLE (-1313 2787);
FORCEPROP 1 LASTPIN (-1125 2775) $PN 2
J 0
(-1163 2787);
DISPLAY 0.787234 (-1163 2787);
PAINT ORANGE (-1163 2787);
DISPLAY INVISIBLE (-1163 2787);
FORCEPROP 2 LAST CDS_LIB mstr_discrete
J 0
(-1225 2775);
PAINT ORANGE (-1225 2775);
DISPLAY INVISIBLE (-1225 2775);
FORCEPROP 2 LAST $SEC 1
J 0
(-1275 2975);
PAINT MONO (-1275 2975);
DISPLAY INVISIBLE (-1275 2975);
FORCEPROP 2 LAST CDS_SEC 1
J 0
(-1275 2975);
PAINT MONO (-1275 2975);
DISPLAY INVISIBLE (-1275 2975);
FORCEPROP 1 LAST PATH I341
J 0
(-1275 2925);
DISPLAY 0.978723 (-1275 2925);
PAINT WHITE (-1275 2925);
DISPLAY INVISIBLE (-1275 2925);
FORCEPROP 2 LAST ROOM PVCCIN_CPU0_VR
J 0
(-1275 2875);
DISPLAY 1.361702 (-1275 2875);
PAINT ORANGE (-1275 2875);
DISPLAY INVISIBLE (-1275 2875);
FORCEADD CAP..1
(-850 1150);
FORCEPROP 1 LASTPIN (-850 1050) $PN 2
J 0
(-840 1030);
DISPLAY 0.617021 (-840 1030);
PAINT ORANGE (-840 1030);
FORCEPROP 1 LASTPIN (-850 1250) $PN 1
J 0
(-840 1230);
DISPLAY 0.617021 (-840 1230);
PAINT ORANGE (-840 1230);
FORCEPROP 1 LAST VOLTAGE 50V
J 0
(-800 1150);
DISPLAY 0.617021 (-800 1150);
PAINT SKYBLUE (-800 1150);
FORCEPROP 1 LAST PACK_TYPE 0402LF
J 0
(-800 1050);
DISPLAY 0.617021 (-800 1050);
PAINT SKYBLUE (-800 1050);
FORCEPROP 1 LAST VALUE 220PF
J 0
(-800 1200);
DISPLAY 0.617021 (-800 1200);
PAINT SKYBLUE (-800 1200);
FORCEPROP 1 LAST LOCATION C7G4
J 0
(-800 1250);
DISPLAY 0.617021 (-800 1250);
PAINT AQUA (-800 1250);
FORCEPROP 1 LAST TOLERANCE 10%
J 0
(-625 1200);
DISPLAY 0.617021 (-625 1200);
PAINT SKYBLUE (-625 1200);
FORCEPROP 1 LAST MATERIAL X7R
J 0
(-675 1150);
DISPLAY 0.617021 (-675 1150);
PAINT SKYBLUE (-675 1150);
FORCEPROP 1 LAST PART_NUMBER A36096-050
J 0
(-800 1100);
DISPLAY 0.617021 (-800 1100);
PAINT BLUE (-800 1100);
FORCEPROP 2 LAST CDS_LOCATION C7G4
J 0
(-800 1250);
DISPLAY 0.617021 (-800 1250);
PAINT AQUA (-800 1250);
DISPLAY INVISIBLE (-800 1250);
FORCEPROP 2 LAST CDS_LIB mstr_discrete
J 0
(-850 1150);
PAINT ORANGE (-850 1150);
DISPLAY INVISIBLE (-850 1150);
FORCEPROP 2 LAST NO_XNET_CONNECTION 1
J 0
(-800 1375);
PAINT MONO (-800 1375);
DISPLAY INVISIBLE (-800 1375);
FORCEPROP 1 LAST PATH I342
J 0
(-800 1300);
DISPLAY 0.978723 (-800 1300);
PAINT WHITE (-800 1300);
DISPLAY INVISIBLE (-800 1300);
FORCEPROP 2 LAST SEC_TYPE 0402LF
J 0
(-800 1375);
DISPLAY 1.021277 (-800 1375);
PAINT ORANGE (-800 1375);
DISPLAY INVISIBLE (-800 1375);
FORCEPROP 2 LAST SEC 1
J 0
(-800 1375);
DISPLAY 0.680851 (-800 1375);
PAINT MONO (-800 1375);
DISPLAY INVISIBLE (-800 1375);
FORCEPROP 2 LAST ROOM VDDQ_ABC_PWR_VR
J 0
(-800 1300);
DISPLAY 1.361702 (-800 1300);
PAINT ORANGE (-800 1300);
DISPLAY INVISIBLE (-800 1300);
FORCEADD RES..1
(-975 1600);
FORCEPROP 1 LAST VALUE 0.0
J 2
(-1075 1500);
DISPLAY 0.617021 (-1075 1500);
PAINT SKYBLUE (-1075 1500);
FORCEPROP 1 LAST WATTAGE 1/16W
J 2
(-1000 1450);
DISPLAY 0.617021 (-1000 1450);
PAINT SKYBLUE (-1000 1450);
FORCEPROP 1 LAST TOLERANCE 5%
J 0
(-1025 1500);
DISPLAY 0.617021 (-1025 1500);
PAINT SKYBLUE (-1025 1500);
FORCEPROP 1 LAST PART_NUMBER G21497-005
J 0
(-1125 1550);
DISPLAY 0.617021 (-1125 1550);
PAINT BLUE (-1125 1550);
FORCEPROP 1 LAST LOCATION R7F21
J 0
(-1025 1650);
DISPLAY 0.617021 (-1025 1650);
PAINT AQUA (-1025 1650);
FORCEPROP 1 LAST MATERIAL CHIP
J 0
(-975 1450);
DISPLAY 0.617021 (-975 1450);
PAINT SKYBLUE (-975 1450);
FORCEPROP 1 LAST PACK_TYPE 0402
J 0
(-900 1500);
DISPLAY 0.617021 (-900 1500);
PAINT SKYBLUE (-900 1500);
FORCEPROP 1 LASTPIN (-1075 1600) $PN 1
J 0
(-1063 1612);
DISPLAY 0.787234 (-1063 1612);
PAINT ORANGE (-1063 1612);
DISPLAY INVISIBLE (-1063 1612);
FORCEPROP 2 LAST ROOM PVCCIN_CPU0_VR
J 0
(-1025 1700);
DISPLAY 1.361702 (-1025 1700);
PAINT ORANGE (-1025 1700);
DISPLAY INVISIBLE (-1025 1700);
FORCEPROP 1 LAST PATH I343
J 0
(-1025 1750);
DISPLAY 0.978723 (-1025 1750);
PAINT WHITE (-1025 1750);
DISPLAY INVISIBLE (-1025 1750);
FORCEPROP 2 LAST CDS_LOCATION R7F21
J 0
(-1025 1650);
DISPLAY 0.617021 (-1025 1650);
PAINT AQUA (-1025 1650);
DISPLAY INVISIBLE (-1025 1650);
FORCEPROP 2 LAST $SEC 1
J 0
(-1025 1800);
PAINT MONO (-1025 1800);
DISPLAY INVISIBLE (-1025 1800);
FORCEPROP 2 LAST CDS_SEC 1
J 0
(-1025 1800);
PAINT MONO (-1025 1800);
DISPLAY INVISIBLE (-1025 1800);
FORCEPROP 1 LASTPIN (-875 1600) $PN 2
J 0
(-913 1612);
DISPLAY 0.787234 (-913 1612);
PAINT ORANGE (-913 1612);
DISPLAY INVISIBLE (-913 1612);
FORCEPROP 2 LAST CDS_LIB mstr_discrete
J 0
(-975 1600);
PAINT ORANGE (-975 1600);
DISPLAY INVISIBLE (-975 1600);
FORCEADD RES..1
(-1125 1325);
FORCEPROP 1 LAST VALUE 10.0
J 2
(-1225 1225);
DISPLAY 0.617021 (-1225 1225);
PAINT SKYBLUE (-1225 1225);
FORCEPROP 1 LAST TOLERANCE 1%
J 0
(-1200 1225);
DISPLAY 0.617021 (-1200 1225);
PAINT SKYBLUE (-1200 1225);
FORCEPROP 1 LAST WATTAGE 1/16W
J 2
(-1125 1175);
DISPLAY 0.617021 (-1125 1175);
PAINT SKYBLUE (-1125 1175);
FORCEPROP 1 LASTPIN (-1225 1325) $PN 1
J 0
(-1213 1337);
DISPLAY 0.617021 (-1213 1337);
PAINT ORANGE (-1213 1337);
FORCEPROP 1 LAST LOCATION R7G9
J 0
(-1175 1375);
DISPLAY 0.617021 (-1175 1375);
PAINT AQUA (-1175 1375);
FORCEPROP 1 LASTPIN (-1025 1325) $PN 2
J 0
(-1063 1337);
DISPLAY 0.617021 (-1063 1337);
PAINT ORANGE (-1063 1337);
FORCEPROP 1 LAST MATERIAL CHIP
J 0
(-1100 1175);
DISPLAY 0.617021 (-1100 1175);
PAINT SKYBLUE (-1100 1175);
FORCEPROP 1 LAST PACK_TYPE 0402
J 0
(-1100 1225);
DISPLAY 0.617021 (-1100 1225);
PAINT SKYBLUE (-1100 1225);
FORCEPROP 1 LAST PART_NUMBER G21796-066
J 0
(-1275 1275);
DISPLAY 0.617021 (-1275 1275);
PAINT BLUE (-1275 1275);
FORCEPROP 2 LAST CDS_LOCATION R7G9
J 0
(-1175 1375);
DISPLAY 0.617021 (-1175 1375);
PAINT AQUA (-1175 1375);
DISPLAY INVISIBLE (-1175 1375);
FORCEPROP 1 LAST PATH I344
J 0
(-1175 1475);
DISPLAY 0.978723 (-1175 1475);
PAINT WHITE (-1175 1475);
DISPLAY INVISIBLE (-1175 1475);
FORCEPROP 2 LAST CDS_LIB mstr_discrete
J 0
(-1125 1325);
PAINT ORANGE (-1125 1325);
DISPLAY INVISIBLE (-1125 1325);
FORCEPROP 2 LAST ROOM VDDQ_ABC_PWR_VR
J 0
(-1050 1425);
DISPLAY 1.361702 (-1050 1425);
PAINT ORANGE (-1050 1425);
DISPLAY INVISIBLE (-1050 1425);
FORCEPROP 2 LAST SEC_TYPE 0402
J 0
(-1175 1550);
DISPLAY 1.021277 (-1175 1550);
PAINT ORANGE (-1175 1550);
DISPLAY INVISIBLE (-1175 1550);
FORCEPROP 2 LAST SEC 1
J 0
(-1175 1550);
DISPLAY 0.680851 (-1175 1550);
PAINT MONO (-1175 1550);
DISPLAY INVISIBLE (-1175 1550);
FORCEPROP 2 LAST NO_XNET_CONNECTION 1
J 0
(-1175 1550);
PAINT MONO (-1175 1550);
DISPLAY INVISIBLE (-1175 1550);
FORCEADD OFFPAGE..2
R 2
(-1950 3575);
FORCEPROP 2 LAST $XR0 215 
J 0
(-2205 3575);
DISPLAY 0.638298 (-2205 3575);
PAINT MONO (-2205 3575);
FORCEPROP 1 LAST OFFPAGE TRUE
J 2
(-2275 3450);
DISPLAY 1.170213 (-2275 3450);
PAINT GREEN (-2275 3450);
DISPLAY INVISIBLE (-2275 3450);
FORCEPROP 2 LAST PATH I345
J 0
(-2200 3625);
DISPLAY 1.021277 (-2200 3625);
PAINT ORANGE (-2200 3625);
DISPLAY INVISIBLE (-2200 3625);
FORCEPROP 2 LAST ROOM VDDQ_ABC_PWR_VR
J 0
(-2500 3650);
DISPLAY 1.361702 (-2500 3650);
PAINT ORANGE (-2500 3650);
DISPLAY INVISIBLE (-2500 3650);
FORCEPROP 1 LAST COMMENT_BODY TRUE
J 2
(-1905 3480);
DISPLAY 1.170213 (-1905 3480);
PAINT GREEN (-1905 3480);
DISPLAY INVISIBLE (-1905 3480);
FORCEPROP 2 LAST CDS_LIB mstr_standard
J 2
(-1950 3575);
PAINT ORANGE (-1950 3575);
DISPLAY INVISIBLE (-1950 3575);
FORCEADD OFFPAGE..1
(-1950 3100);
FORCEPROP 2 LAST $XR0 21 
J 0
(-2171 3100);
DISPLAY 0.638298 (-2171 3100);
PAINT MONO (-2171 3100);
FORCEPROP 2 LAST $XR1 194 
J 0
(-2291 3100);
DISPLAY 0.638298 (-2291 3100);
PAINT MONO (-2291 3100);
FORCEPROP 2 LAST $XR2 218 
J 0
(-2411 3100);
DISPLAY 0.638298 (-2411 3100);
PAINT MONO (-2411 3100);
FORCEPROP 2 LAST PATH I346
J 0
(-2200 3150);
DISPLAY 1.021277 (-2200 3150);
PAINT ORANGE (-2200 3150);
DISPLAY INVISIBLE (-2200 3150);
FORCEPROP 2 LAST ROOM VDDQ_ABC_PWR_VR
J 0
(-2500 3175);
DISPLAY 1.361702 (-2500 3175);
PAINT ORANGE (-2500 3175);
DISPLAY INVISIBLE (-2500 3175);
FORCEPROP 1 LAST COMMENT_BODY TRUE
J 0
(-1825 3000);
DISPLAY 1.170213 (-1825 3000);
PAINT GREEN (-1825 3000);
DISPLAY INVISIBLE (-1825 3000);
FORCEPROP 1 LAST OFFPAGE TRUE
J 0
(-1625 2975);
DISPLAY 1.170213 (-1625 2975);
PAINT GREEN (-1625 2975);
DISPLAY INVISIBLE (-1625 2975);
FORCEPROP 2 LAST CDS_LIB mstr_standard
J 0
(-1950 3100);
PAINT ORANGE (-1950 3100);
DISPLAY INVISIBLE (-1950 3100);
FORCEADD OFFPAGE..1
(-2000 2775);
FORCEPROP 2 LAST $XR0 215 
J 0
(-2252 2775);
DISPLAY 0.638298 (-2252 2775);
PAINT MONO (-2252 2775);
FORCEPROP 2 LAST PATH I347
J 0
(-2250 2825);
DISPLAY 1.021277 (-2250 2825);
PAINT ORANGE (-2250 2825);
DISPLAY INVISIBLE (-2250 2825);
FORCEPROP 2 LAST ROOM VDDQ_ABC_PWR_VR
J 0
(-2550 2850);
DISPLAY 1.361702 (-2550 2850);
PAINT ORANGE (-2550 2850);
DISPLAY INVISIBLE (-2550 2850);
FORCEPROP 2 LAST CDS_LIB mstr_standard
J 0
(-2000 2775);
PAINT ORANGE (-2000 2775);
DISPLAY INVISIBLE (-2000 2775);
FORCEPROP 1 LAST COMMENT_BODY TRUE
J 0
(-1875 2675);
DISPLAY 1.170213 (-1875 2675);
PAINT GREEN (-1875 2675);
DISPLAY INVISIBLE (-1875 2675);
FORCEPROP 1 LAST OFFPAGE TRUE
J 0
(-1675 2650);
DISPLAY 1.170213 (-1675 2650);
PAINT GREEN (-1675 2650);
DISPLAY INVISIBLE (-1675 2650);
FORCEADD OFFPAGE..1
(-1950 2450);
FORCEPROP 2 LAST $XR0 216 
J 0
(-2202 2450);
DISPLAY 0.638298 (-2202 2450);
PAINT MONO (-2202 2450);
FORCEPROP 2 LAST PATH I348
J 0
(-2200 2500);
DISPLAY 1.021277 (-2200 2500);
PAINT ORANGE (-2200 2500);
DISPLAY INVISIBLE (-2200 2500);
FORCEPROP 2 LAST ROOM VDDQ_ABC_PWR_VR
J 0
(-2500 2525);
DISPLAY 1.361702 (-2500 2525);
PAINT ORANGE (-2500 2525);
DISPLAY INVISIBLE (-2500 2525);
FORCEPROP 2 LAST CDS_LIB mstr_standard
J 0
(-1950 2450);
PAINT ORANGE (-1950 2450);
DISPLAY INVISIBLE (-1950 2450);
FORCEPROP 1 LAST COMMENT_BODY TRUE
J 0
(-1825 2350);
DISPLAY 1.170213 (-1825 2350);
PAINT GREEN (-1825 2350);
DISPLAY INVISIBLE (-1825 2350);
FORCEPROP 1 LAST OFFPAGE TRUE
J 0
(-1625 2325);
DISPLAY 1.170213 (-1625 2325);
PAINT GREEN (-1625 2325);
DISPLAY INVISIBLE (-1625 2325);
FORCEADD OFFPAGE..1
(-1950 2400);
FORCEPROP 2 LAST $XR0 216 
J 0
(-2202 2400);
DISPLAY 0.638298 (-2202 2400);
PAINT MONO (-2202 2400);
FORCEPROP 2 LAST ROOM VDDQ_ABC_PWR_VR
J 0
(-2500 2475);
DISPLAY 1.361702 (-2500 2475);
PAINT ORANGE (-2500 2475);
DISPLAY INVISIBLE (-2500 2475);
FORCEPROP 2 LAST PATH I349
J 0
(-2200 2450);
DISPLAY 1.021277 (-2200 2450);
PAINT ORANGE (-2200 2450);
DISPLAY INVISIBLE (-2200 2450);
FORCEPROP 1 LAST COMMENT_BODY TRUE
J 0
(-1825 2300);
DISPLAY 1.170213 (-1825 2300);
PAINT GREEN (-1825 2300);
DISPLAY INVISIBLE (-1825 2300);
FORCEPROP 2 LAST CDS_LIB mstr_standard
J 0
(-1950 2400);
PAINT ORANGE (-1950 2400);
DISPLAY INVISIBLE (-1950 2400);
FORCEPROP 1 LAST OFFPAGE TRUE
J 0
(-1625 2275);
DISPLAY 1.170213 (-1625 2275);
PAINT GREEN (-1625 2275);
DISPLAY INVISIBLE (-1625 2275);
FORCEADD OFFPAGE..1
(-1950 2250);
FORCEPROP 2 LAST $XR0 216 
J 0
(-2202 2250);
DISPLAY 0.638298 (-2202 2250);
PAINT MONO (-2202 2250);
FORCEPROP 2 LASTPIN (-1900 2250) SIG_NAME ISENSE_PVDDQ_ABC_PH1_IMON
J 0
(-1905 2265);
DISPLAY 0.617021 (-1905 2265);
PAINT ORANGE (-1905 2265);
FORCEPROP 2 LAST ROOM VDDQ_ABC_PWR_VR
J 0
(-2500 2325);
DISPLAY 1.361702 (-2500 2325);
PAINT ORANGE (-2500 2325);
DISPLAY INVISIBLE (-2500 2325);
FORCEPROP 2 LAST PATH I350
J 0
(-2200 2300);
DISPLAY 1.021277 (-2200 2300);
PAINT ORANGE (-2200 2300);
DISPLAY INVISIBLE (-2200 2300);
FORCEPROP 2 LAST CDS_LIB mstr_standard
J 0
(-1950 2250);
PAINT ORANGE (-1950 2250);
DISPLAY INVISIBLE (-1950 2250);
FORCEPROP 1 LAST COMMENT_BODY TRUE
J 0
(-1825 2150);
DISPLAY 1.170213 (-1825 2150);
PAINT GREEN (-1825 2150);
DISPLAY INVISIBLE (-1825 2150);
FORCEPROP 1 LAST OFFPAGE TRUE
J 0
(-1625 2125);
DISPLAY 1.170213 (-1625 2125);
PAINT GREEN (-1625 2125);
DISPLAY INVISIBLE (-1625 2125);
FORCEADD OFFPAGE..1
(-1950 2200);
FORCEPROP 2 LAST $XR0 216 
J 0
(-2202 2200);
DISPLAY 0.638298 (-2202 2200);
PAINT MONO (-2202 2200);
FORCEPROP 2 LASTPIN (-1900 2200) SIG_NAME ISENSE_PVDDQ_ABC_PH2_IMON
J 0
(-1905 2215);
DISPLAY 0.617021 (-1905 2215);
PAINT ORANGE (-1905 2215);
FORCEPROP 2 LAST ROOM VDDQ_ABC_PWR_VR
J 0
(-2500 2275);
DISPLAY 1.361702 (-2500 2275);
PAINT ORANGE (-2500 2275);
DISPLAY INVISIBLE (-2500 2275);
FORCEPROP 2 LAST PATH I351
J 0
(-2200 2250);
DISPLAY 1.021277 (-2200 2250);
PAINT ORANGE (-2200 2250);
DISPLAY INVISIBLE (-2200 2250);
FORCEPROP 2 LAST CDS_LIB mstr_standard
J 0
(-1950 2200);
PAINT ORANGE (-1950 2200);
DISPLAY INVISIBLE (-1950 2200);
FORCEPROP 1 LAST COMMENT_BODY TRUE
J 0
(-1825 2100);
DISPLAY 1.170213 (-1825 2100);
PAINT GREEN (-1825 2100);
DISPLAY INVISIBLE (-1825 2100);
FORCEPROP 1 LAST OFFPAGE TRUE
J 0
(-1625 2075);
DISPLAY 1.170213 (-1625 2075);
PAINT GREEN (-1625 2075);
DISPLAY INVISIBLE (-1625 2075);
FORCEADD OFFPAGE..1
(-1950 1900);
FORCEPROP 2 LAST $XR0 216 
J 0
(-2202 1900);
DISPLAY 0.638298 (-2202 1900);
PAINT MONO (-2202 1900);
FORCEPROP 2 LAST ROOM VDDQ_ABC_PWR_VR
J 0
(-2500 1975);
DISPLAY 1.361702 (-2500 1975);
PAINT ORANGE (-2500 1975);
DISPLAY INVISIBLE (-2500 1975);
FORCEPROP 2 LAST PATH I352
J 0
(-2200 1950);
DISPLAY 1.021277 (-2200 1950);
PAINT ORANGE (-2200 1950);
DISPLAY INVISIBLE (-2200 1950);
FORCEPROP 2 LAST CDS_LIB mstr_standard
J 0
(-1950 1900);
PAINT ORANGE (-1950 1900);
DISPLAY INVISIBLE (-1950 1900);
FORCEPROP 1 LAST COMMENT_BODY TRUE
J 0
(-1825 1800);
DISPLAY 1.170213 (-1825 1800);
PAINT GREEN (-1825 1800);
DISPLAY INVISIBLE (-1825 1800);
FORCEPROP 1 LAST OFFPAGE TRUE
J 0
(-1625 1775);
DISPLAY 1.170213 (-1625 1775);
PAINT GREEN (-1625 1775);
DISPLAY INVISIBLE (-1625 1775);
FORCEADD OFFPAGE..1
(-1950 2000);
FORCEPROP 2 LAST $XR0 197 
J 0
(-2202 2000);
DISPLAY 0.638298 (-2202 2000);
PAINT MONO (-2202 2000);
FORCEPROP 2 LAST ROOM VDDQ_ABC_PWR_VR
J 0
(-2500 2075);
DISPLAY 1.361702 (-2500 2075);
PAINT ORANGE (-2500 2075);
DISPLAY INVISIBLE (-2500 2075);
FORCEPROP 2 LAST PATH I353
J 0
(-2200 2050);
DISPLAY 1.021277 (-2200 2050);
PAINT ORANGE (-2200 2050);
DISPLAY INVISIBLE (-2200 2050);
FORCEPROP 2 LAST CDS_LIB mstr_standard
J 0
(-1950 2000);
PAINT ORANGE (-1950 2000);
DISPLAY INVISIBLE (-1950 2000);
FORCEPROP 1 LAST COMMENT_BODY TRUE
J 0
(-1825 1900);
DISPLAY 1.170213 (-1825 1900);
PAINT GREEN (-1825 1900);
DISPLAY INVISIBLE (-1825 1900);
FORCEPROP 1 LAST OFFPAGE TRUE
J 0
(-1625 1875);
DISPLAY 1.170213 (-1625 1875);
PAINT GREEN (-1625 1875);
DISPLAY INVISIBLE (-1625 1875);
FORCEADD OFFPAGE..1
(-1950 2050);
FORCEPROP 2 LAST $XR0 215 
J 0
(-2202 2050);
DISPLAY 0.638298 (-2202 2050);
PAINT MONO (-2202 2050);
FORCEPROP 2 LAST ROOM VDDQ_ABC_PWR_VR
J 0
(-2500 2125);
DISPLAY 1.361702 (-2500 2125);
PAINT ORANGE (-2500 2125);
DISPLAY INVISIBLE (-2500 2125);
FORCEPROP 2 LAST PATH I354
J 0
(-2200 2100);
DISPLAY 1.021277 (-2200 2100);
PAINT ORANGE (-2200 2100);
DISPLAY INVISIBLE (-2200 2100);
FORCEPROP 1 LAST COMMENT_BODY TRUE
J 0
(-1825 1950);
DISPLAY 1.170213 (-1825 1950);
PAINT GREEN (-1825 1950);
DISPLAY INVISIBLE (-1825 1950);
FORCEPROP 1 LAST OFFPAGE TRUE
J 0
(-1625 1925);
DISPLAY 1.170213 (-1625 1925);
PAINT GREEN (-1625 1925);
DISPLAY INVISIBLE (-1625 1925);
FORCEPROP 2 LAST CDS_LIB mstr_standard
J 0
(-1950 2050);
PAINT ORANGE (-1950 2050);
DISPLAY INVISIBLE (-1950 2050);
FORCEADD OFFPAGE..1
(-1950 1600);
FORCEPROP 2 LAST $XR0 191 
J 0
(-2202 1600);
DISPLAY 0.638298 (-2202 1600);
PAINT MONO (-2202 1600);
FORCEPROP 2 LAST ROOM VDDQ_ABC_PWR_VR
J 0
(-2500 1675);
DISPLAY 1.361702 (-2500 1675);
PAINT ORANGE (-2500 1675);
DISPLAY INVISIBLE (-2500 1675);
FORCEPROP 2 LAST PATH I355
J 0
(-2200 1650);
DISPLAY 1.021277 (-2200 1650);
PAINT ORANGE (-2200 1650);
DISPLAY INVISIBLE (-2200 1650);
FORCEPROP 1 LAST OFFPAGE TRUE
J 0
(-1625 1475);
DISPLAY 1.170213 (-1625 1475);
PAINT GREEN (-1625 1475);
DISPLAY INVISIBLE (-1625 1475);
FORCEPROP 1 LAST COMMENT_BODY TRUE
J 0
(-1825 1500);
DISPLAY 1.170213 (-1825 1500);
PAINT GREEN (-1825 1500);
DISPLAY INVISIBLE (-1825 1500);
FORCEPROP 2 LAST CDS_LIB mstr_standard
J 0
(-1950 1600);
PAINT ORANGE (-1950 1600);
DISPLAY INVISIBLE (-1950 1600);
FORCEADD OFFPAGE..1
(-1950 1325);
FORCEPROP 2 LAST $XR0 217 
J 0
(-2202 1325);
DISPLAY 0.638298 (-2202 1325);
PAINT MONO (-2202 1325);
FORCEPROP 2 LAST PATH I356
J 0
(-2200 1375);
DISPLAY 1.021277 (-2200 1375);
PAINT ORANGE (-2200 1375);
DISPLAY INVISIBLE (-2200 1375);
FORCEPROP 2 LAST ROOM VDDQ_ABC_PWR_VR
J 0
(-2500 1400);
DISPLAY 1.361702 (-2500 1400);
PAINT ORANGE (-2500 1400);
DISPLAY INVISIBLE (-2500 1400);
FORCEPROP 1 LAST COMMENT_BODY TRUE
J 0
(-1825 1225);
DISPLAY 1.170213 (-1825 1225);
PAINT GREEN (-1825 1225);
DISPLAY INVISIBLE (-1825 1225);
FORCEPROP 1 LAST OFFPAGE TRUE
J 0
(-1625 1200);
DISPLAY 1.170213 (-1625 1200);
PAINT GREEN (-1625 1200);
DISPLAY INVISIBLE (-1625 1200);
FORCEPROP 2 LAST CDS_LIB mstr_standard
J 0
(-1950 1325);
PAINT ORANGE (-1950 1325);
DISPLAY INVISIBLE (-1950 1325);
FORCEADD OFFPAGE..1
(-1950 975);
FORCEPROP 2 LAST $XR0 217 
J 0
(-2202 975);
DISPLAY 0.638298 (-2202 975);
PAINT MONO (-2202 975);
FORCEPROP 2 LAST PATH I357
J 0
(-2200 1025);
DISPLAY 1.021277 (-2200 1025);
PAINT ORANGE (-2200 1025);
DISPLAY INVISIBLE (-2200 1025);
FORCEPROP 2 LAST ROOM VDDQ_ABC_PWR_VR
J 0
(-2500 1050);
DISPLAY 1.361702 (-2500 1050);
PAINT ORANGE (-2500 1050);
DISPLAY INVISIBLE (-2500 1050);
FORCEPROP 1 LAST COMMENT_BODY TRUE
J 0
(-1825 875);
DISPLAY 1.170213 (-1825 875);
PAINT GREEN (-1825 875);
DISPLAY INVISIBLE (-1825 875);
FORCEPROP 1 LAST OFFPAGE TRUE
J 0
(-1625 850);
DISPLAY 1.170213 (-1625 850);
PAINT GREEN (-1625 850);
DISPLAY INVISIBLE (-1625 850);
FORCEPROP 2 LAST CDS_LIB mstr_standard
J 0
(-1950 975);
PAINT ORANGE (-1950 975);
DISPLAY INVISIBLE (-1950 975);
FORCEADD PXM1310B..2
(1725 1900);
FORCEPROP 1 LAST PART_NUMBER H89186-001
J 0
(1325 950);
DISPLAY 0.617021 (1325 950);
PAINT BLUE (1325 950);
FORCEPROP 2 LASTPIN (1275 1050) $PN 33
J 2
(1265 1060);
DISPLAY 0.617021 (1265 1060);
PAINT MONO (1265 1060);
FORCEPROP 2 LASTPIN (1275 1100) $PN 36
J 2
(1265 1110);
DISPLAY 0.617021 (1265 1110);
PAINT MONO (1265 1110);
FORCEPROP 2 LASTPIN (1275 1200) $PN 32
J 2
(1265 1210);
DISPLAY 0.617021 (1265 1210);
PAINT MONO (1265 1210);
FORCEPROP 2 LASTPIN (1275 1250) $PN 31
J 2
(1265 1260);
DISPLAY 0.617021 (1265 1260);
PAINT MONO (1265 1260);
FORCEPROP 2 LASTPIN (1275 1350) $PN 8
J 2
(1265 1360);
DISPLAY 0.617021 (1265 1360);
PAINT MONO (1265 1360);
FORCEPROP 2 LASTPIN (1275 1450) $PN 30
J 2
(1265 1460);
DISPLAY 0.617021 (1265 1460);
PAINT MONO (1265 1460);
FORCEPROP 2 LASTPIN (1275 1500) $PN 20
J 2
(1265 1510);
DISPLAY 0.617021 (1265 1510);
PAINT MONO (1265 1510);
FORCEPROP 2 LASTPIN (1275 1700) $PN 29
J 2
(1265 1710);
DISPLAY 0.617021 (1265 1710);
PAINT MONO (1265 1710);
FORCEPROP 2 LASTPIN (1275 1600) $PN 10
J 2
(1265 1610);
DISPLAY 0.617021 (1265 1610);
PAINT MONO (1265 1610);
FORCEPROP 2 LASTPIN (1275 1750) $PN 19
J 2
(1265 1760);
DISPLAY 0.617021 (1265 1760);
PAINT MONO (1265 1760);
FORCEPROP 2 LASTPIN (1275 1900) $PN 35
J 2
(1265 1910);
DISPLAY 0.617021 (1265 1910);
PAINT MONO (1265 1910);
FORCEPROP 2 LASTPIN (1275 1850) $PN 34
J 2
(1265 1860);
DISPLAY 0.617021 (1265 1860);
PAINT MONO (1265 1860);
FORCEPROP 2 LASTPIN (1275 2000) $PN 38
J 2
(1265 2010);
DISPLAY 0.617021 (1265 2010);
PAINT MONO (1265 2010);
FORCEPROP 2 LASTPIN (1275 2050) $PN 37
J 2
(1265 2060);
DISPLAY 0.617021 (1265 2060);
PAINT MONO (1265 2060);
FORCEPROP 2 LASTPIN (1275 2150) $PN 26
J 2
(1265 2160);
DISPLAY 0.617021 (1265 2160);
PAINT MONO (1265 2160);
FORCEPROP 2 LASTPIN (1275 2200) $PN 24
J 2
(1265 2210);
DISPLAY 0.617021 (1265 2210);
PAINT MONO (1265 2210);
FORCEPROP 2 LASTPIN (1275 2250) $PN 22
J 2
(1265 2260);
DISPLAY 0.617021 (1265 2260);
PAINT MONO (1265 2260);
FORCEPROP 2 LASTPIN (1275 2350) $PN 25
J 2
(1265 2360);
DISPLAY 0.617021 (1265 2360);
PAINT MONO (1265 2360);
FORCEPROP 2 LASTPIN (1275 2400) $PN 23
J 2
(1265 2410);
DISPLAY 0.617021 (1265 2410);
PAINT MONO (1265 2410);
FORCEPROP 2 LASTPIN (1275 2450) $PN 21
J 2
(1265 2460);
DISPLAY 0.617021 (1265 2460);
PAINT MONO (1265 2460);
FORCEPROP 2 LASTPIN (1275 2550) $PN 15
J 2
(1265 2560);
DISPLAY 0.617021 (1265 2560);
PAINT MONO (1265 2560);
FORCEPROP 2 LASTPIN (1275 2650) $PN 39
J 2
(1265 2660);
DISPLAY 0.617021 (1265 2660);
PAINT MONO (1265 2660);
FORCEPROP 1 LAST MATERIAL IC
J 0
(1325 2825);
DISPLAY 0.617021 (1325 2825);
PAINT SKYBLUE (1325 2825);
FORCEPROP 1 LAST LOCATION EU7G1
J 0
(1325 2875);
DISPLAY 0.617021 (1325 2875);
PAINT AQUA (1325 2875);
FORCEPROP 2 LASTPIN (2175 1200) $PN 41
J 0
(2185 1210);
DISPLAY 0.617021 (2185 1210);
PAINT MONO (2185 1210);
FORCEPROP 2 LASTPIN (2175 1100) $PN 27
J 0
(2185 1110);
DISPLAY 0.617021 (2185 1110);
PAINT MONO (2185 1110);
FORCEPROP 2 LASTPIN (2175 1500) $PN 3
J 0
(2185 1510);
DISPLAY 0.617021 (2185 1510);
PAINT MONO (2185 1510);
FORCEPROP 2 LASTPIN (2175 1300) $PN 2
J 0
(2185 1310);
DISPLAY 0.617021 (2185 1310);
PAINT MONO (2185 1310);
FORCEPROP 2 LASTPIN (2175 1350) $PN 28
J 0
(2185 1360);
DISPLAY 0.617021 (2185 1360);
PAINT MONO (2185 1360);
FORCEPROP 2 LASTPIN (2175 1600) $PN 5
J 0
(2185 1610);
DISPLAY 0.617021 (2185 1610);
PAINT MONO (2185 1610);
FORCEPROP 2 LASTPIN (2175 1550) $PN 4
J 0
(2185 1560);
DISPLAY 0.617021 (2185 1560);
PAINT MONO (2185 1560);
FORCEPROP 2 LASTPIN (2175 1650) $PN 1
J 0
(2185 1660);
DISPLAY 0.617021 (2185 1660);
PAINT MONO (2185 1660);
FORCEPROP 2 LASTPIN (2175 2000) $PN 13
J 0
(2185 2010);
DISPLAY 0.617021 (2185 2010);
PAINT MONO (2185 2010);
FORCEPROP 2 LASTPIN (2175 1950) $PN 14
J 0
(2185 1960);
DISPLAY 0.617021 (2185 1960);
PAINT MONO (2185 1960);
FORCEPROP 2 LASTPIN (2175 1850) $PN 40
J 0
(2185 1860);
DISPLAY 0.617021 (2185 1860);
PAINT MONO (2185 1860);
FORCEPROP 2 LASTPIN (2175 1800) $PN 16
J 0
(2185 1810);
DISPLAY 0.617021 (2185 1810);
PAINT MONO (2185 1810);
FORCEPROP 2 LASTPIN (2175 2250) $PN 12
J 0
(2185 2260);
DISPLAY 0.617021 (2185 2260);
PAINT MONO (2185 2260);
FORCEPROP 2 LASTPIN (2175 2150) $PN 7
J 0
(2185 2160);
DISPLAY 0.617021 (2185 2160);
PAINT MONO (2185 2160);
FORCEPROP 2 LASTPIN (2175 2100) $PN 6
J 0
(2185 2110);
DISPLAY 0.617021 (2185 2110);
PAINT MONO (2185 2110);
FORCEPROP 2 LASTPIN (2175 2350) $PN 18
J 0
(2185 2360);
DISPLAY 0.617021 (2185 2360);
PAINT MONO (2185 2360);
FORCEPROP 2 LASTPIN (2175 2500) $PN 17
J 0
(2185 2510);
DISPLAY 0.617021 (2185 2510);
PAINT MONO (2185 2510);
FORCEPROP 2 LASTPIN (2175 2550) $PN 11
J 0
(2185 2560);
DISPLAY 0.617021 (2185 2560);
PAINT MONO (2185 2560);
FORCEPROP 2 LASTPIN (2175 2650) $PN 9
J 0
(2185 2660);
DISPLAY 0.617021 (2185 2660);
PAINT MONO (2185 2660);
FORCEPROP 1 LAST CDS_LMAN_SYM_OUTLINE -400,900,400,-900
J 0
(1725 1900);
DISPLAY 0.468085 (1725 1900);
PAINT GREEN (1725 1900);
DISPLAY INVISIBLE (1725 1900);
FORCEPROP 2 LAST CDS_LIB mstr_controller
J 0
(1725 1900);
PAINT ORANGE (1725 1900);
DISPLAY INVISIBLE (1725 1900);
FORCEPROP 1 LAST PACK_TYPE QFN
J 0
(1325 2925);
PAINT SKYBLUE (1325 2925);
DISPLAY INVISIBLE (1325 2925);
FORCEPROP 2 LAST CDS_SEC 1
J 0
(1325 2925);
PAINT MONO (1325 2925);
DISPLAY INVISIBLE (1325 2925);
FORCEPROP 2 LAST $SEC 1
J 0
(1325 2925);
PAINT MONO (1325 2925);
DISPLAY INVISIBLE (1325 2925);
FORCEPROP 2 LAST CDS_LOCATION EU7G1
J 0
(1325 2875);
PAINT WHITE (1325 2875);
DISPLAY INVISIBLE (1325 2875);
FORCEPROP 1 LAST PATH I358
J 0
(1825 2826);
PAINT WHITE (1825 2826);
DISPLAY INVISIBLE (1825 2826);
FORCEADD GND..1
(-75 150);
FORCEPROP 3 LASTPIN (-75 200) SIG_NAME GND\g
J 0
(-65 210);
DISPLAY 0.659574 (-65 210);
PAINT MONO (-65 210);
DISPLAY INVISIBLE (-65 210);
FORCEPROP 1 LAST BODY_TYPE PLUMBING
J 0
(-120 107);
DISPLAY 0.340426 (-120 107);
PAINT GREEN (-120 107);
DISPLAY INVISIBLE (-120 107);
FORCEPROP 1 LAST VOLTAGE 0.0V
J 0
(-120 107);
DISPLAY 0.340426 (-120 107);
PAINT SKYBLUE (-120 107);
DISPLAY INVISIBLE (-120 107);
FORCEPROP 2 LAST CDS_LIB mstr_symbols
J 0
(-75 150);
PAINT ORANGE (-75 150);
DISPLAY INVISIBLE (-75 150);
FORCEPROP 1 LAST HDL_POWER GND
J 0
(-75 300);
DISPLAY 1.170213 (-75 300);
PAINT GREEN (-75 300);
DISPLAY INVISIBLE (-75 300);
FORCEPROP 1 LAST PATH I359
J 0
(0 150);
DISPLAY 0.872340 (0 150);
PAINT AQUA (0 150);
DISPLAY INVISIBLE (0 150);
FORCEPROP 1 LAST SIZE 1B
J 0
(0 100);
DISPLAY 1.170213 (0 100);
PAINT AQUA (0 100);
DISPLAY INVISIBLE (0 100);
FORCEADD CAP_A..1
R 2
(-75 525);
FORCEPROP 1 LAST PART_NUMBER A36096-030
J 2
(-125 375);
DISPLAY 0.617021 (-125 375);
PAINT BLUE (-125 375);
FORCEPROP 1 LAST PACK_TYPE 0402V
J 2
(-125 325);
DISPLAY 0.617021 (-125 325);
PAINT SKYBLUE (-125 325);
FORCEPROP 1 LASTPIN (-75 425) $PN 2
J 2
(-85 405);
DISPLAY 0.617021 (-85 405);
PAINT ORANGE (-85 405);
FORCEPROP 1 LAST MATERIAL X7R
J 2
(-125 425);
DISPLAY 0.617021 (-125 425);
PAINT SKYBLUE (-125 425);
FORCEPROP 1 LAST TOLERANCE 10%
J 2
(-125 475);
DISPLAY 0.617021 (-125 475);
PAINT SKYBLUE (-125 475);
FORCEPROP 1 LAST VALUE 0.1UF
J 2
(-125 575);
DISPLAY 0.617021 (-125 575);
PAINT SKYBLUE (-125 575);
FORCEPROP 1 LAST LOCATION C3U10
J 2
(-125 625);
DISPLAY 0.617021 (-125 625);
PAINT AQUA (-125 625);
FORCEPROP 1 LAST VOLTAGE 16V
J 2
(-125 525);
DISPLAY 0.617021 (-125 525);
PAINT SKYBLUE (-125 525);
FORCEPROP 1 LASTPIN (-75 625) $PN 1
J 2
(-85 605);
DISPLAY 0.617021 (-85 605);
PAINT ORANGE (-85 605);
FORCEPROP 0 LAST ROOM VDDQ_ABC_PWR_VR
J 0
(-125 675);
DISPLAY 1.021277 (-125 675);
PAINT ORANGE (-125 675);
DISPLAY INVISIBLE (-125 675);
FORCEPROP 2 LAST CDS_LIB dev_discrete
J 0
(-75 525);
PAINT ORANGE (-75 525);
DISPLAY INVISIBLE (-75 525);
FORCEPROP 1 LAST PATH I360
J 2
(-125 675);
DISPLAY 0.978723 (-125 675);
PAINT WHITE (-125 675);
DISPLAY INVISIBLE (-125 675);
FORCEPROP 2 LAST SEC_TYPE 0402V
J 0
(-125 725);
DISPLAY 1.021277 (-125 725);
PAINT ORANGE (-125 725);
DISPLAY INVISIBLE (-125 725);
FORCEPROP 2 LAST SEC 1
J 0
(-125 725);
DISPLAY 0.680851 (-125 725);
PAINT MONO (-125 725);
DISPLAY INVISIBLE (-125 725);
FORCEPROP 2 LAST CDS_SEC 1
J 0
(-125 675);
PAINT ORANGE (-125 675);
DISPLAY INVISIBLE (-125 675);
FORCEADD DNS..2
(-95 3620);
PAINT RED (-95 3620);
FORCEPROP 1 LAST COMMENT_BODY TRUE
R 1
J 0
(-20 3395);
DISPLAY 0.872340 (-20 3395);
PAINT GREEN (-20 3395);
DISPLAY INVISIBLE (-20 3395);
FORCEPROP 2 LAST CDS_LIB mstr_misc
J 0
(-95 3620);
PAINT ORANGE (-95 3620);
DISPLAY INVISIBLE (-95 3620);
FORCEADD DESIGN_NOTE..1
(1150 800);
FORCEPROP 0 LAST L1 SMBUS ADDRESS: 0X50
J 0
(950 675);
DISPLAY 1.021277 (950 675);
PAINT ORANGE (950 675);
FORCEPROP 0 LAST L2 SVID ADDRESS=0X0
J 0
(946 613);
DISPLAY 1.021277 (946 613);
PAINT ORANGE (946 613);
FORCEPROP 1 LAST COMMENT_BODY TRUE
J 0
(1175 900);
DISPLAY 0.978723 (1175 900);
PAINT ORANGE (1175 900);
DISPLAY INVISIBLE (1175 900);
FORCEPROP 2 LAST CDS_LIB mstr_symbols
J 0
(1150 800);
PAINT ORANGE (1150 800);
DISPLAY INVISIBLE (1150 800);
FORCEADD DNS..2
(3080 3045);
PAINT RED (3080 3045);
FORCEPROP 1 LAST COMMENT_BODY TRUE
R 1
J 0
(3155 2820);
DISPLAY 0.872340 (3155 2820);
PAINT GREEN (3155 2820);
DISPLAY INVISIBLE (3155 2820);
FORCEPROP 2 LAST CDS_LIB mstr_misc
J 0
(3080 3045);
PAINT ORANGE (3080 3045);
DISPLAY INVISIBLE (3080 3045);
FORCEADD DESIGN_NOTE..1
(4550 4025);
PAINT PURPLE (4550 4025);
FORCEPROP 0 LAST L1 SMBUS ADDRESS 0X50
J 0
(4375 3900);
PAINT VIOLET (4375 3900);
FORCEPROP 0 LAST L2 SVID ADDRESS=0X0
J 0
(4380 3840);
DISPLAY 1.021277 (4380 3840);
PAINT ORANGE (4380 3840);
FORCEPROP 2 LAST BOM_COST SM_CONTROLLER
J 0
(4350 3975);
PAINT MONO (4350 3975);
DISPLAY INVISIBLE (4350 3975);
FORCEPROP 2 LAST CDS_LIB mstr_symbols
J 0
(4550 4025);
PAINT MONO (4550 4025);
DISPLAY INVISIBLE (4550 4025);
FORCEPROP 2 LAST ROOM VDDQ_ABC_PWR_VR
J 0
(4350 3975);
PAINT MONO (4350 3975);
DISPLAY INVISIBLE (4350 3975);
FORCEPROP 1 LAST COMMENT_BODY TRUE
J 0
(4575 4125);
DISPLAY 1.319149 (4575 4125);
PAINT GREEN (4575 4125);
DISPLAY INVISIBLE (4575 4125);
FORCEADD DNS..2
(430 3620);
PAINT RED (430 3620);
FORCEPROP 1 LAST COMMENT_BODY TRUE
R 1
J 0
(505 3395);
DISPLAY 0.872340 (505 3395);
PAINT GREEN (505 3395);
DISPLAY INVISIBLE (505 3395);
FORCEPROP 2 LAST CDS_LIB mstr_misc
J 0
(430 3620);
PAINT ORANGE (430 3620);
DISPLAY INVISIBLE (430 3620);
FORCEADD INTEL_CORP_BPAGE..1
(5575 -775);
FORCEPROP 1 LAST CDS_CON_LAST_MODIFIED Tue Dec 01 11:52:25 2015
J 0
(4150 -450);
DISPLAY 0.744681 (4150 -450);
PAINT GREEN (4150 -450);
DISPLAY INVISIBLE (4150 -450);
FORCEPROP 1 LAST CUSTOM_TXT_CDS <CURRENT_DESIGN_SHEET> OF <TOTAL_DESIGN_SHEETS>
J 0
(5075 -750);
PAINT GREEN (5075 -750);
FORCEPROP 1 LAST CUSTOM_TXT_CDS <CON_LAST_MODIFIED>
J 0
(3650 -425);
PAINT GREEN (3650 -425);
FORCEPROP 2 LAST CUSTOM_TXT_CDS <XR_PAGE_TITLE>
J 0
(-2315 4475);
DISPLAY 0.638298 (-2315 4475);
PAINT PINK (-2315 4475);
DISPLAY INVISIBLE (-2315 4475);
FORCEPROP 1 LAST SCH_TITLE VDDQ ABC VR (1 OF 3)
J 0
(-2400 -750);
DISPLAY 1.212766 (-2400 -750);
PAINT ORANGE (-2400 -750);
FORCEPROP 1 LAST SCH_ADDRESS2 P.O. BOX 58119
J 0
(1600 -700);
DISPLAY 0.617021 (1600 -700);
PAINT GREEN (1600 -700);
FORCEPROP 1 LAST SCH_ADDRESS1 2200 Mission College Blvd.
J 0
(1600 -650);
DISPLAY 0.617021 (1600 -650);
PAINT GREEN (1600 -650);
FORCEPROP 1 LAST SCH_ADDRESS3 Santa Clara, CA 95052-8119
J 0
(1600 -750);
DISPLAY 0.617021 (1600 -750);
PAINT GREEN (1600 -750);
FORCEPROP 1 LAST SCH_NUMBER H4694802
J 0
(4275 -625);
DISPLAY 1.212766 (4275 -625);
PAINT YELLOW (4275 -625);
FORCEPROP 1 LAST SCH_DEPT BESD
J 1
(1125 -675);
DISPLAY 1.212766 (1125 -675);
PAINT YELLOW (1125 -675);
FORCEPROP 1 LAST SCH_REV 2.420
J 0
(5325 -625);
DISPLAY 0.978723 (5325 -625);
PAINT YELLOW (5325 -625);
FORCEPROP 2 LAST PAGE_BORDER TRUE
J 0
(-2315 4475);
DISPLAY 0.638298 (-2315 4475);
PAINT PINK (-2315 4475);
DISPLAY INVISIBLE (-2315 4475);
FORCEPROP 1 LAST COMMENT_BODY TRUE
J 0
(5587 -763);
DISPLAY 0.340426 (5587 -763);
PAINT GREEN (5587 -763);
DISPLAY INVISIBLE (5587 -763);
FORCEPROP 2 LAST CDS_LIB mstr_symbols
J 0
(5575 -775);
DISPLAY 0.744681 (5575 -775);
PAINT ORANGE (5575 -775);
DISPLAY INVISIBLE (5575 -775);
FORCEPROP 2 LAST ROOM VDDQ_ABC_PWR_VR
J 0
(5125 4375);
DISPLAY 0.744681 (5125 4375);
PAINT ORANGE (5125 4375);
DISPLAY INVISIBLE (5125 4375);
FORCEPROP 2 LAST CDS_XR_PAGE_TITLE CR-215 : @BASEBOARD_FAB2_LIB.BASEBOARD_FAB2(SCH_1):PAGE215
J 0
(-2315 4475);
DISPLAY 0.638298 (-2315 4475);
PAINT PINK (-2315 4475);
DISPLAY INVISIBLE (-2315 4475);
WIRE 16 -1 (4100 3025)(4100 3100);
WIRE 16 -1 (2400 3300)(2400 3650);
WIRE 16 -1 (2400 3650)(2750 3650);
WIRE 16 -1 (2750 3300)(2750 3650);
WIRE 16 -1 (2950 3650)(2750 3650);
WIRE 16 -1 (3075 3650)(2950 3650);
WIRE 16 -1 (2950 3650)(2950 3825);
WIRE 16 -1 (3075 3150)(3075 3650);
WIRE 16 -1 (3225 1250)(3225 1125);
WIRE 16 -1 (2175 1200)(2300 1200);
WIRE 16 -1 (2300 1200)(2300 1100);
WIRE 16 -1 (2175 1100)(2300 1100);
WIRE 16 -1 (2300 975)(2300 1100);
WIRE 16 -1 (1825 3050)(1825 3100);
WIRE 16 -1 (1425 3050)(1425 3100);
WIRE 16 -1 (425 3725)(425 3875);
WIRE 16 -1 (425 3875)(1125 3875);
WIRE 16 -1 (1125 3650)(1125 3875);
WIRE 16 -1 (1125 3875)(1125 3925);
WIRE 16 -1 (850 200)(850 300);
WIRE 16 -1 (1275 1200)(400 1200);
WIRE 16 -1 (400 1200)(400 1000);
WIRE 16 -1 (500 200)(500 300);
WIRE 16 -1 (325 200)(325 750);
WIRE 16 -1 (3000 275)(3000 400);
WIRE 16 -1 (2600 350)(2600 400);
WIRE 16 -1 (-100 3725)(-100 3850);
WIRE 16 -1 (-950 3875)(-950 3950);
WIRE 16 -1 (-950 3200)(-950 3300);
WIRE 16 -1 (-1175 3200)(-1175 3300);
WIRE 16 -1 (-75 200)(-75 425);
WIRE 16 -1 (-950 3575)(-950 3675);
WIRE 16 -1 (-950 3500)(-950 3575);
WIRE 16 -1 (-950 3575)(-1175 3575);
WIRE 16 -1 (-1175 3500)(-1175 3575);
WIRE 16 -1 (-1175 3575)(-1900 3575);
FORCEPROP 2 LAST SIG_NAME VR_PVDDQ_ABC_VINSEN
J 0
(-1915 3590);
DISPLAY 0.617021 (-1915 3590);
PAINT ORANGE (-1915 3590);
WIRE 16 -1 (-1900 3100)(-100 3100);
FORCEPROP 0 LAST SIG_NAME SVID_CLK1_CPU0_R
J 0
(-1900 3110);
DISPLAY 0.617021 (-1900 3110);
PAINT ORANGE (-1900 3110);
WIRE 16 -1 (25 3100)(-100 3100);
WIRE 16 -1 (-100 3525)(-100 3100);
WIRE 16 2175 (5450 3675)(5450 3175);
WIRE 16 2175 (5450 3675)(4375 3675);
WIRE 16 2175 (5450 3175)(4375 3175);
WIRE 16 2175 (4375 3175)(4375 3675);
WIRE 16 -1 (4100 2825)(4100 1800);
WIRE 16 -1 (4100 1800)(4275 1800);
WIRE 16 -1 (3175 1800)(4100 1800);
FORCEPROP 2 LAST SIG_NAME SVID_DIO1_CPU0_R
J 0
(3625 1810);
DISPLAY 0.617021 (3625 1810);
PAINT ORANGE (3625 1810);
WIRE 16 -1 (3600 2650)(4275 2650);
FORCEPROP 2 LAST SIG_NAME PWRGD_PVDDQ_ABC
J 0
(3760 2665);
DISPLAY 0.617021 (3760 2665);
PAINT ORANGE (3760 2665);
WIRE 16 -1 (4275 2550)(3525 2550);
FORCEPROP 2 LAST SIG_NAME IRQ_PVDDQ_ABC_VRHOT_LVT3_N
J 0
(3710 2565);
DISPLAY 0.617021 (3710 2565);
PAINT ORANGE (3710 2565);
WIRE 16 -1 (3025 2500)(4275 2500);
FORCEPROP 2 LAST SIG_NAME SVID_ALERT1_CPU0_R_N
J 0
(3775 2510);
DISPLAY 0.617021 (3775 2510);
PAINT ORANGE (3775 2510);
WIRE 16 -1 (3500 2150)(4275 2150);
FORCEPROP 2 LAST SIG_NAME SMB_VR_STBY_LVC3_SCL
J 0
(3735 2165);
DISPLAY 0.617021 (3735 2165);
PAINT ORANGE (3735 2165);
WIRE 16 -1 (3175 2100)(4275 2100);
FORCEPROP 2 LAST SIG_NAME SMB_VR_STBY_LVC3_SDA
J 0
(3735 2115);
DISPLAY 0.617021 (3735 2115);
PAINT ORANGE (3735 2115);
WIRE 16 -1 (4300 1850)(2175 1850);
FORCEPROP 2 LAST SIG_NAME VR_PVDDQ_ABC_VD12
J 0
(3610 1865);
DISPLAY 0.617021 (3610 1865);
PAINT ORANGE (3610 1865);
WIRE 16 -1 (4300 1600)(2175 1600);
FORCEPROP 2 LAST SIG_NAME VR_PVDDQ_ABC_PWM1
J 0
(3600 1615);
DISPLAY 0.617021 (3600 1615);
PAINT ORANGE (3600 1615);
WIRE 16 -1 (2175 1550)(4300 1550);
FORCEPROP 2 LAST SIG_NAME VR_PVDDQ_ABC_PWM2
J 0
(3600 1565);
DISPLAY 0.617021 (3600 1565);
PAINT ORANGE (3600 1565);
WIRE 16 -1 (3400 2650)(3225 2650);
WIRE 16 -1 (3225 2650)(2750 2650);
FORCEPROP 2 LAST SIG_NAME PWRGD_PVDDQ_ABC_R
J 0
(2810 2665);
DISPLAY 0.617021 (2810 2665);
PAINT ORANGE (2810 2665);
FORCEPROP 2 LASTPROP $XRERR UNIQUE?
J 0
(2570 2665);
DISPLAY 0.638298 (2570 2665);
PAINT MONO (2570 2665);
DISPLAY INVISIBLE (2570 2665);
WIRE 16 -1 (3225 2650)(3225 1450);
WIRE 16 -1 (2750 3100)(2750 2650);
WIRE 16 -1 (2175 2650)(2750 2650);
WIRE 16 -1 (3075 2375)(3075 2950);
WIRE 16 -1 (2900 2375)(3075 2375);
WIRE 16 -1 (2900 2000)(2900 2375);
WIRE 16 -1 (2175 2000)(2900 2000);
FORCEPROP 2 LAST SIG_NAME PU_VR_PVDDQ_ABC_FAULT1
J 0
(2285 2015);
DISPLAY 0.617021 (2285 2015);
PAINT ORANGE (2285 2015);
FORCEPROP 2 LASTPROP $XRERR UNIQUE?
J 0
(2045 2015);
DISPLAY 0.638298 (2045 2015);
PAINT MONO (2045 2015);
DISPLAY INVISIBLE (2045 2015);
WIRE 16 -1 (2175 2150)(3300 2150);
FORCEPROP 2 LAST SIG_NAME SMB_VR_SCL_VDDQ_ABC
J 0
(2275 2165);
DISPLAY 0.617021 (2275 2165);
PAINT ORANGE (2275 2165);
FORCEPROP 2 LASTPROP $XRERR UNIQUE?
J 0
(2035 2165);
DISPLAY 0.638298 (2035 2165);
PAINT MONO (2035 2165);
DISPLAY INVISIBLE (2035 2165);
WIRE 16 -1 (3325 2550)(2400 2550);
FORCEPROP 2 LAST SIG_NAME IRQ_PVDDQ_ABC_VRHOT_LVT3_R_N
J 0
(2260 2565);
DISPLAY 0.617021 (2260 2565);
PAINT ORANGE (2260 2565);
FORCEPROP 2 LASTPROP $XRERR UNIQUE?
J 0
(2020 2565);
DISPLAY 0.638298 (2020 2565);
PAINT MONO (2020 2565);
DISPLAY INVISIBLE (2020 2565);
WIRE 16 -1 (2400 3100)(2400 2550);
WIRE 16 -1 (2400 2550)(2175 2550);
WIRE 16 -1 (2175 2350)(2825 2350);
FORCEPROP 2 LAST SIG_NAME TP_PVDDQ_ABC_MP2
J 0
(2275 2365);
DISPLAY 0.617021 (2275 2365);
PAINT ORANGE (2275 2365);
FORCEPROP 2 LASTPROP $XRERR UNIQUE?
J 0
(2855 2350);
DISPLAY 0.638298 (2855 2350);
PAINT MONO (2855 2350);
DISPLAY INVISIBLE (2855 2350);
WIRE 16 -1 (2175 2250)(2825 2250);
FORCEPROP 2 LAST SIG_NAME TP_PVDDQ_ABC_PINALRT_N
J 0
(2275 2265);
DISPLAY 0.617021 (2275 2265);
PAINT ORANGE (2275 2265);
FORCEPROP 2 LASTPROP $XRERR UNIQUE?
J 0
(2855 2250);
DISPLAY 0.638298 (2855 2250);
PAINT MONO (2855 2250);
DISPLAY INVISIBLE (2855 2250);
WIRE 16 -1 (2175 2100)(2975 2100);
FORCEPROP 2 LAST SIG_NAME SMB_VR_SDA_VDDQ_ABC
J 0
(2275 2115);
DISPLAY 0.617021 (2275 2115);
PAINT ORANGE (2275 2115);
FORCEPROP 2 LASTPROP $XRERR UNIQUE?
J 0
(2035 2115);
DISPLAY 0.638298 (2035 2115);
PAINT MONO (2035 2115);
DISPLAY INVISIBLE (2035 2115);
WIRE 16 -1 (2825 2500)(2175 2500);
FORCEPROP 2 LAST SIG_NAME SVID_ALERT_PVDDQ_ABC
J 0
(2275 2515);
DISPLAY 0.617021 (2275 2515);
PAINT ORANGE (2275 2515);
FORCEPROP 2 LASTPROP $XRERR UNIQUE?
J 0
(2035 2515);
DISPLAY 0.638298 (2035 2515);
PAINT MONO (2035 2515);
DISPLAY INVISIBLE (2035 2515);
WIRE 16 -1 (3000 600)(3000 675);
WIRE 16 -1 (3000 675)(3500 675);
WIRE 16 -1 (3000 675)(2600 675);
FORCEPROP 2 LAST SIG_NAME VR_PVDDQ_ABC_VD12
J 0
(2685 690);
DISPLAY 0.617021 (2685 690);
PAINT ORANGE (2685 690);
WIRE 16 -1 (2600 600)(2600 675);
WIRE 16 -1 (2175 1650)(2975 1650);
FORCEPROP 2 LAST SIG_NAME TP_PVDDQ_ABC_BPWM1
J 0
(2275 1665);
DISPLAY 0.617021 (2275 1665);
PAINT ORANGE (2275 1665);
FORCEPROP 2 LASTPROP $XRERR UNIQUE?
J 0
(3005 1650);
DISPLAY 0.638298 (3005 1650);
PAINT MONO (3005 1650);
DISPLAY INVISIBLE (3005 1650);
WIRE 16 -1 (2175 1500)(2975 1500);
FORCEPROP 2 LAST SIG_NAME TP_PVDDQ_ABC_PWM3
J 0
(2275 1515);
DISPLAY 0.617021 (2275 1515);
PAINT ORANGE (2275 1515);
FORCEPROP 2 LASTPROP $XRERR UNIQUE?
J 0
(3005 1500);
DISPLAY 0.638298 (3005 1500);
PAINT MONO (3005 1500);
DISPLAY INVISIBLE (3005 1500);
WIRE 16 -1 (2175 1800)(2975 1800);
FORCEPROP 2 LAST SIG_NAME SVID_VDIO_PVDDQ_ABC
J 0
(2275 1815);
DISPLAY 0.617021 (2275 1815);
PAINT ORANGE (2275 1815);
FORCEPROP 2 LASTPROP $XRERR UNIQUE?
J 0
(2035 1815);
DISPLAY 0.638298 (2035 1815);
PAINT MONO (2035 1815);
DISPLAY INVISIBLE (2035 1815);
WIRE 16 -1 (2175 1300)(2975 1300);
FORCEPROP 2 LAST SIG_NAME NC_PVDDQ_ABC_DNC0
J 0
(2275 1315);
DISPLAY 0.617021 (2275 1315);
PAINT ORANGE (2275 1315);
FORCEPROP 2 LASTPROP $XRERR UNIQUE?
J 0
(3005 1300);
DISPLAY 0.638298 (3005 1300);
PAINT MONO (3005 1300);
DISPLAY INVISIBLE (3005 1300);
WIRE 16 -1 (2175 1350)(2975 1350);
FORCEPROP 2 LAST SIG_NAME NC_PVDDQ_ABC_DNC1
J 0
(2275 1365);
DISPLAY 0.617021 (2275 1365);
PAINT ORANGE (2275 1365);
FORCEPROP 2 LASTPROP $XRERR UNIQUE?
J 0
(3005 1350);
DISPLAY 0.638298 (3005 1350);
PAINT MONO (3005 1350);
DISPLAY INVISIBLE (3005 1350);
WIRE 16 -1 (2175 1950)(2875 1950);
FORCEPROP 2 LAST SIG_NAME TP_PVDDQ_ABC_MP1
J 0
(2275 1965);
DISPLAY 0.617021 (2275 1965);
PAINT ORANGE (2275 1965);
FORCEPROP 2 LASTPROP $XRERR UNIQUE?
J 0
(2905 1950);
DISPLAY 0.638298 (2905 1950);
PAINT MONO (2905 1950);
DISPLAY INVISIBLE (2905 1950);
WIRE 16 -1 (1825 3300)(1825 3350);
WIRE 16 -1 (1825 3350)(1425 3350);
FORCEPROP 2 LAST SIG_NAME VR_PVDDQ_ABC_VDD
J 0
(1385 3365);
DISPLAY 0.617021 (1385 3365);
PAINT ORANGE (1385 3365);
FORCEPROP 2 LASTPROP $XRERR UNIQUE?
J 0
(1145 3365);
DISPLAY 0.638298 (1145 3365);
PAINT MONO (1145 3365);
DISPLAY INVISIBLE (1145 3365);
WIRE 16 -1 (1425 3300)(1425 3350);
WIRE 16 -1 (1425 3350)(1125 3350);
WIRE 16 -1 (1125 3450)(1125 3350);
WIRE 16 -1 (1125 3350)(1125 2650);
WIRE 16 -1 (1275 2650)(1125 2650);
WIRE 16 -1 (950 2550)(1275 2550);
WIRE 16 -1 (950 3100)(950 2550);
WIRE 16 -1 (225 3100)(950 3100);
FORCEPROP 2 LAST SIG_NAME SVID_CLK_PVDDQ_ABC
J 0
(485 3115);
DISPLAY 0.617021 (485 3115);
PAINT ORANGE (485 3115);
FORCEPROP 2 LASTPROP $XRERR UNIQUE?
J 0
(245 3115);
DISPLAY 0.638298 (245 3115);
PAINT MONO (245 3115);
DISPLAY INVISIBLE (245 3115);
WIRE 16 -1 (500 2150)(1275 2150);
FORCEPROP 2 LAST SIG_NAME TP_PVDDQ_ABC_PH3_IMON
J 0
(525 2165);
DISPLAY 0.617021 (525 2165);
PAINT ORANGE (525 2165);
FORCEPROP 2 LASTPROP $XRERR UNIQUE?
J 0
(260 2150);
DISPLAY 0.638298 (260 2150);
PAINT MONO (260 2150);
DISPLAY INVISIBLE (260 2150);
WIRE 16 -1 (500 2350)(1275 2350);
FORCEPROP 2 LAST SIG_NAME TP_PVDDQ_ABC_PH3_IMON_REF
J 0
(550 2365);
DISPLAY 0.617021 (550 2365);
PAINT ORANGE (550 2365);
FORCEPROP 2 LASTPROP $XRERR UNIQUE?
J 0
(260 2350);
DISPLAY 0.638298 (260 2350);
PAINT MONO (260 2350);
DISPLAY INVISIBLE (260 2350);
WIRE 16 -1 (425 1600)(425 3525);
WIRE 16 -1 (425 1600)(1275 1600);
FORCEPROP 2 LAST SIG_NAME VR_PVDDQ_ABC_VREN
J 0
(550 1610);
DISPLAY 0.617021 (550 1610);
PAINT ORANGE (550 1610);
FORCEPROP 2 LASTPROP $XRERR UNIQUE?
J 0
(310 1610);
DISPLAY 0.638298 (310 1610);
PAINT MONO (310 1610);
DISPLAY INVISIBLE (310 1610);
WIRE 16 -1 (-875 1600)(425 1600);
WIRE 16 -1 (325 950)(325 1900);
WIRE 16 -1 (325 1900)(1275 1900);
WIRE 16 -1 (-1900 1900)(325 1900);
FORCEPROP 2 LAST SIG_NAME A_TSENSE_PVDDQ_ABC
J 0
(-1925 1915);
DISPLAY 0.617021 (-1925 1915);
PAINT ORANGE (-1925 1915);
WIRE 16 -1 (850 1050)(1275 1050);
WIRE 16 -1 (850 500)(850 1050);
FORCEPROP 0 LAST SIG_NAME VR_PVDDQ_ABC_XADDR2
R 1
J 0
(840 510);
DISPLAY 0.617021 (840 510);
PAINT ORANGE (840 510);
FORCEPROP 2 LASTPROP $XRERR UNIQUE?
J 0
(600 510);
DISPLAY 0.638298 (600 510);
PAINT MONO (600 510);
DISPLAY INVISIBLE (600 510);
WIRE 16 -1 (575 1350)(1275 1350);
FORCEPROP 2 LAST SIG_NAME TP_PVDDQ_ABC_RESET_N
J 0
(675 1365);
DISPLAY 0.617021 (675 1365);
PAINT ORANGE (675 1365);
FORCEPROP 2 LASTPROP $XRERR UNIQUE?
J 0
(335 1350);
DISPLAY 0.638298 (335 1350);
PAINT MONO (335 1350);
DISPLAY INVISIBLE (335 1350);
WIRE 16 -1 (500 1100)(1275 1100);
WIRE 16 -1 (500 500)(500 1100);
FORCEPROP 0 LAST SIG_NAME VR_PVDDQ_ABC_XADDR1
R 1
J 0
(490 535);
DISPLAY 0.617021 (490 535);
PAINT ORANGE (490 535);
FORCEPROP 2 LASTPROP $XRERR UNIQUE?
J 0
(250 535);
DISPLAY 0.638298 (250 535);
PAINT MONO (250 535);
DISPLAY INVISIBLE (250 535);
WIRE 16 -1 (575 1850)(1275 1850);
FORCEPROP 2 LAST SIG_NAME TP_PVDDQ_ABC_BTSEN
J 0
(675 1865);
DISPLAY 0.617021 (675 1865);
PAINT ORANGE (675 1865);
FORCEPROP 2 LASTPROP $XRERR UNIQUE?
J 0
(335 1850);
DISPLAY 0.638298 (335 1850);
PAINT MONO (335 1850);
DISPLAY INVISIBLE (335 1850);
WIRE 16 -1 (575 1250)(1275 1250);
FORCEPROP 2 LAST SIG_NAME TP_PVDDQ_ABC_BREF1
J 0
(675 1265);
DISPLAY 0.617021 (675 1265);
PAINT ORANGE (675 1265);
FORCEPROP 2 LASTPROP $XRERR UNIQUE?
J 0
(335 1250);
DISPLAY 0.638298 (335 1250);
PAINT MONO (335 1250);
DISPLAY INVISIBLE (335 1250);
WIRE 16 -1 (575 1700)(1275 1700);
FORCEPROP 2 LAST SIG_NAME TP_PVDDQ_ABC_BVSEN
J 0
(675 1715);
DISPLAY 0.617021 (675 1715);
PAINT ORANGE (675 1715);
FORCEPROP 2 LASTPROP $XRERR UNIQUE?
J 0
(335 1700);
DISPLAY 0.638298 (335 1700);
PAINT MONO (335 1700);
DISPLAY INVISIBLE (335 1700);
WIRE 16 -1 (575 1450)(1275 1450);
FORCEPROP 2 LAST SIG_NAME TP_PVDDQ_ABC_BVREF
J 0
(675 1465);
DISPLAY 0.617021 (675 1465);
PAINT ORANGE (675 1465);
FORCEPROP 2 LASTPROP $XRERR UNIQUE?
J 0
(335 1450);
DISPLAY 0.638298 (335 1450);
PAINT MONO (335 1450);
DISPLAY INVISIBLE (335 1450);
WIRE 16 -1 (1275 1500)(-150 1500);
WIRE 16 -1 (-150 975)(-150 1500);
WIRE 16 -1 (-850 975)(-150 975);
WIRE 16 -1 (-850 1050)(-850 975);
WIRE 16 -1 (-850 975)(-1900 975);
FORCEPROP 2 LAST SIG_NAME VSENSE_PVDDQ_ABC_N
J 0
(-1915 990);
DISPLAY 0.617021 (-1915 990);
PAINT ORANGE (-1915 990);
WIRE 16 -1 (1275 1750)(-300 1750);
WIRE 16 -1 (-300 1325)(-300 1750);
WIRE 16 -1 (-850 1325)(-300 1325);
FORCEPROP 2 LAST SIG_NAME VR_PVDDQ_ABC_AVSP
J 0
(-790 1340);
DISPLAY 0.617021 (-790 1340);
PAINT ORANGE (-790 1340);
FORCEPROP 2 LASTPROP $XRERR UNIQUE?
J 0
(-1030 1340);
DISPLAY 0.638298 (-1030 1340);
PAINT MONO (-1030 1340);
DISPLAY INVISIBLE (-1030 1340);
WIRE 16 -1 (-850 1250)(-850 1325);
WIRE 16 -1 (-1025 1325)(-850 1325);
WIRE 16 -1 (-1000 2450)(1275 2450);
WIRE 16 -1 (-1000 2775)(-1000 2450);
WIRE 16 -1 (-1900 2450)(-1000 2450);
FORCEPROP 2 LAST SIG_NAME VR_PVDDQ_ABC_AIREF1
J 0
(-1890 2465);
DISPLAY 0.617021 (-1890 2465);
PAINT ORANGE (-1890 2465);
WIRE 16 -1 (-1125 2775)(-1000 2775);
WIRE 16 -1 (-25 2400)(1275 2400);
WIRE 16 -1 (-25 2925)(-25 2400);
WIRE 16 -1 (-1900 2400)(-25 2400);
FORCEPROP 2 LAST SIG_NAME VR_PVDDQ_ABC_AIREF2
J 0
(-1890 2415);
DISPLAY 0.617021 (-1890 2415);
PAINT ORANGE (-1890 2415);
WIRE 16 -1 (-200 2925)(-25 2925);
WIRE 16 -1 (1275 2000)(-75 2000);
WIRE 16 -1 (-75 625)(-75 2000);
WIRE 16 -1 (-75 2000)(-1900 2000);
FORCEPROP 2 LAST SIG_NAME VR_PVDDQ_ABC_AIINSEN
J 0
(-1910 2010);
DISPLAY 0.617021 (-1910 2010);
PAINT ORANGE (-1910 2010);
WIRE 16 -1 (-1900 2250)(1275 2250);
WIRE 16 -1 (-1900 2200)(1275 2200);
WIRE 16 -1 (1275 2050)(-1900 2050);
FORCEPROP 2 LAST SIG_NAME VR_PVDDQ_ABC_VINSEN
J 0
(-1925 2065);
DISPLAY 0.617021 (-1925 2065);
PAINT ORANGE (-1925 2065);
WIRE 16 -1 (-1425 2925)(-400 2925);
WIRE 16 -1 (-1425 2775)(-1425 2925);
WIRE 16 -1 (-1425 2775)(-1325 2775);
WIRE 16 -1 (-1950 2775)(-1425 2775);
FORCEPROP 2 LAST SIG_NAME VR_PVDDQ_ABC_VD12
J 0
(-1915 2790);
DISPLAY 0.617021 (-1915 2790);
PAINT ORANGE (-1915 2790);
WIRE 16 -1 (-1900 1600)(-1075 1600);
FORCEPROP 2 LAST SIG_NAME FM_PVDDQ_ABC_EN
J 0
(-1875 1610);
DISPLAY 0.617021 (-1875 1610);
PAINT ORANGE (-1875 1610);
WIRE 16 -1 (-1225 1325)(-1900 1325);
FORCEPROP 2 LAST SIG_NAME VSENSE_PVDDQ_ABC_P
J 0
(-1915 1340);
DISPLAY 0.617021 (-1915 1340);
PAINT ORANGE (-1915 1340);
DOT 1 (-850 975);
DOT 1 (-850 1325);
DOT 1 (-75 2000);
DOT 1 (-1425 2775);
DOT 1 (-1175 3575);
DOT 1 (-1000 2450);
DOT 1 (-25 2400);
DOT 1 (-950 3575);
DOT 1 (-100 3100);
DOT 1 (425 1600);
DOT 1 (325 1900);
DOT 1 (1125 3350);
DOT 1 (1425 3350);
DOT 1 (1125 3875);
DOT 1 (3000 675);
DOT 1 (2300 1100);
DOT 1 (2400 2550);
DOT 1 (2750 2650);
DOT 1 (2750 3650);
DOT 1 (2950 3650);
DOT 1 (3225 2650);
DOT 1 (4100 1800);
FORCENOTE
ROOM=VDDQ_ABC_PWR_VR
(-2305 -665) 0;
DISPLAY LEFT (-2305 -665);
DISPLAY 2.446809 (-2305 -665);
PAINT PURPLE (-2305 -665);
FORCENOTE
VOUT = 1.2V 
(4400 3600) 0;
DISPLAY LEFT (4400 3600);
DISPLAY 0.808511 (4400 3600);
PAINT PURPLE (4400 3600);
FORCENOTE
DC TOL = +/-0.5%
(4400 3500) 0;
DISPLAY LEFT (4400 3500);
DISPLAY 0.808511 (4400 3500);
PAINT PURPLE (4400 3500);
FORCENOTE
IOUT TDC = 63A
(4400 3400) 0;
DISPLAY LEFT (4400 3400);
DISPLAY 0.808511 (4400 3400);
PAINT PURPLE (4400 3400);
FORCENOTE
IOUT PK =74A
(4400 3350) 0;
DISPLAY LEFT (4400 3350);
DISPLAY 0.808511 (4400 3350);
PAINT PURPLE (4400 3350);
FORCENOTE
IOUT STEP = 45A
(4400 3300) 0;
DISPLAY LEFT (4400 3300);
DISPLAY 0.808511 (4400 3300);
PAINT PURPLE (4400 3300);
FORCENOTE
IOUT DI/DT = 15A/US
(4400 3250) 0;
DISPLAY LEFT (4400 3250);
DISPLAY 0.808511 (4400 3250);
PAINT PURPLE (4400 3250);
FORCENOTE
RIPPLE GUIDELINE = +/- 0.5%
(4400 3550) 0;
DISPLAY LEFT (4400 3550);
DISPLAY 0.808511 (4400 3550);
PAINT PURPLE (4400 3550);
FORCENOTE
AC & RIPPLE TOL = +/2.8%
(4400 3450) 0;
DISPLAY LEFT (4400 3450);
DISPLAY 0.808511 (4400 3450);
PAINT PURPLE (4400 3450);
FORCENOTE
SW FREQ = 833.33KHZ
(4400 3200) 0;
DISPLAY LEFT (4400 3200);
DISPLAY 0.808511 (4400 3200);
PAINT PURPLE (4400 3200);
QUIT
